%FSTAX23Y23*%
%MOIN*%
%SFA1B1*%

%IPPOS*%
%ADD143C,0.120000*%
%ADD158C,0.061020*%
%ADD160C,0.075000*%
%ADD161C,0.098430*%
%ADD162O,0.088580X0.177170*%
%ADD163O,0.177170X0.088580*%
%ADD171C,0.016000*%
%ADD172C,0.200000*%
%LNgrandmaster-1*%
%LPD*%
G36*
X07078Y00509D02*
X03114D01*
Y00225*
X02294*
Y00314*
X02262Y00346*
X02234*
X02202Y00314*
Y00225*
X01781*
Y00341*
X01784Y00342*
X01786Y00343*
X01791Y00339*
X01797Y00338*
X01804Y00339*
X01809Y00343*
X01812Y00348*
X01814Y00355*
X01812Y00361*
X01809Y00366*
X01804Y0037*
X01797Y00371*
X01791Y0037*
X01786Y00366*
X01784Y00367*
X01781Y00368*
Y00469*
X01735Y00515*
X01663*
X01618Y0047*
Y00312*
X01321*
Y00512*
X00581*
Y00188*
X00007*
Y04354*
X00019Y04366*
X07078*
Y00509*
G37*
%LNgrandmaster-2*%
%LPC*%
G36*
X0257Y04299D02*
X02564Y04298D01*
X02559Y04294*
X02555Y04289*
X02554Y04283*
X02555Y04276*
X02559Y04271*
X02564Y04267*
X0257Y04266*
X02577Y04267*
X02582Y04271*
X02585Y04276*
X02587Y04283*
X02585Y04289*
X02582Y04294*
X02577Y04298*
X0257Y04299*
G37*
G36*
X01294Y04272D02*
X01288Y04271D01*
X01283Y04267*
X01279Y04262*
X01278Y04256*
X01279Y04249*
X01283Y04244*
X01288Y0424*
X01294Y04239*
X01301Y0424*
X01306Y04244*
X01309Y04249*
X01311Y04256*
X01309Y04262*
X01306Y04267*
X01301Y04271*
X01294Y04272*
G37*
G36*
X02078Y04293D02*
X02007D01*
Y04222*
X02078*
Y04293*
G37*
G36*
X01493Y04289D02*
X01422D01*
Y04218*
X01493*
Y04289*
G37*
G36*
X01557Y04245D02*
X01551Y04244D01*
X01546Y0424*
X01542Y04235*
X01541Y04229*
X01542Y04222*
X01546Y04217*
X01551Y04213*
X01557Y04212*
X01564Y04213*
X01569Y04217*
X01572Y04222*
X01574Y04229*
X01572Y04235*
X01569Y0424*
X01564Y04244*
X01557Y04245*
G37*
G36*
X01345Y04191D02*
X01339Y0419D01*
X01333Y04186*
X0133Y04181*
X01329Y04175*
X0133Y04168*
X01333Y04163*
X01339Y0416*
X01345Y04158*
X01351Y0416*
X01357Y04163*
X0136Y04168*
X01361Y04175*
X0136Y04181*
X01357Y04186*
X01351Y0419*
X01345Y04191*
G37*
G36*
X01569Y04187D02*
X01563Y04186D01*
X01558Y04182*
X01554Y04177*
X01553Y04171*
X01554Y04165*
X01558Y04159*
X01563Y04156*
X01569Y04154*
X01576Y04156*
X01581Y04159*
X01584Y04165*
X01586Y04171*
X01584Y04177*
X01581Y04182*
X01576Y04186*
X01569Y04187*
G37*
G36*
X01779Y04172D02*
X01773Y04171D01*
X01768Y04167*
X01764Y04162*
X01763Y04156*
X01764Y04149*
X01768Y04144*
X01773Y0414*
X01779Y04139*
X01786Y0414*
X01791Y04144*
X01794Y04149*
X01796Y04156*
X01794Y04162*
X01791Y04167*
X01786Y04171*
X01779Y04172*
G37*
G36*
X02043Y04193D02*
X02034Y04192D01*
X02025Y04188*
X02017Y04183*
X02012Y04175*
X02008Y04167*
X02007Y04157*
X02008Y04148*
X02012Y04139*
X02017Y04132*
X02025Y04126*
X02034Y04123*
X02043Y04122*
X02052Y04123*
X02061Y04126*
X02068Y04132*
X02074Y04139*
X02077Y04148*
X02079Y04157*
X02077Y04167*
X02074Y04175*
X02068Y04183*
X02061Y04188*
X02052Y04192*
X02043Y04193*
G37*
G36*
X01457Y04189D02*
X01448Y04188D01*
X01439Y04184*
X01432Y04179*
X01426Y04171*
X01423Y04163*
X01421Y04153*
X01423Y04144*
X01426Y04136*
X01432Y04128*
X01439Y04122*
X01448Y04119*
X01457Y04118*
X01466Y04119*
X01475Y04122*
X01483Y04128*
X01488Y04136*
X01492Y04144*
X01493Y04153*
X01492Y04163*
X01488Y04171*
X01483Y04179*
X01475Y04184*
X01466Y04188*
X01457Y04189*
G37*
G36*
X03958Y04152D02*
X03951Y04151D01*
X03945Y04148*
X03939Y04144*
X03935Y04139*
X03933Y04132*
X03932Y04126*
X03933Y04119*
X03935Y04113*
X03939Y04107*
X03945Y04103*
X03951Y04101*
X03958Y041*
X03964Y04101*
X03971Y04103*
X03976Y04107*
X0398Y04113*
X03983Y04119*
X03984Y04126*
X03983Y04132*
X0398Y04139*
X03976Y04144*
X03971Y04148*
X03964Y04151*
X03958Y04152*
G37*
G36*
X03784D02*
X03778Y04151D01*
X03771Y04148*
X03766Y04144*
X03762Y04139*
X03759Y04132*
X03758Y04126*
X03759Y04119*
X03762Y04113*
X03766Y04107*
X03771Y04103*
X03778Y04101*
X03784Y041*
X03791Y04101*
X03797Y04103*
X03803Y04107*
X03807Y04113*
X03809Y04119*
X0381Y04126*
X03809Y04132*
X03807Y04139*
X03803Y04144*
X03797Y04148*
X03791Y04151*
X03784Y04152*
G37*
G36*
X04754Y04132D02*
X04748Y04131D01*
X04743Y04127*
X04739Y04122*
X04738Y04115*
X04739Y04109*
X04743Y04104*
X04748Y041*
X04754Y04099*
X0476Y041*
X04766Y04104*
X04769Y04109*
X04771Y04115*
X04769Y04122*
X04766Y04127*
X0476Y04131*
X04754Y04132*
G37*
G36*
X02146Y0412D02*
X02139Y04118D01*
X02134Y04115*
X02131Y0411*
X02129Y04103*
X02131Y04097*
X02134Y04092*
X02139Y04088*
X02146Y04087*
X02152Y04088*
X02157Y04092*
X02161Y04097*
X02162Y04103*
X02161Y0411*
X02157Y04115*
X02152Y04118*
X02146Y0412*
G37*
G36*
X05267Y04105D02*
X0526Y04103D01*
X05255Y041*
X05251Y04095*
X0525Y04088*
X05251Y04082*
X05255Y04077*
X0526Y04073*
X05267Y04072*
X05273Y04073*
X05278Y04077*
X05282Y04082*
X05283Y04088*
X05282Y04095*
X05278Y041*
X05273Y04103*
X05267Y04105*
G37*
G36*
X02253Y04102D02*
X02247Y04101D01*
X02242Y04098*
X02238Y04092*
X02237Y04086*
X02238Y0408*
X02242Y04075*
X02247Y04071*
X02253Y0407*
X0226Y04071*
X02265Y04075*
X02269Y0408*
X0227Y04086*
X02269Y04092*
X02265Y04098*
X0226Y04101*
X02253Y04102*
G37*
G36*
X03504Y04102D02*
X03498Y04101D01*
X03493Y04097*
X03489Y04092*
X03488Y04086*
X03489Y04079*
X03493Y04074*
X03498Y0407*
X03504Y04069*
X03511Y0407*
X03516Y04074*
X03519Y04079*
X03521Y04086*
X03519Y04092*
X03516Y04097*
X03511Y04101*
X03504Y04102*
G37*
G36*
X03294Y04127D02*
X03284Y04126D01*
X03274Y04121*
X03265Y04115*
X03259Y04106*
X03254Y04096*
X03253Y04086*
X03254Y04075*
X03259Y04065*
X03265Y04056*
X03274Y0405*
X03284Y04046*
X03294Y04044*
X03305Y04046*
X03315Y0405*
X03324Y04056*
X0333Y04065*
X03334Y04075*
X03336Y04086*
X03334Y04096*
X0333Y04106*
X03324Y04115*
X03315Y04121*
X03305Y04126*
X03294Y04127*
G37*
G36*
X02994D02*
X02984Y04126D01*
X02974Y04121*
X02965Y04115*
X02959Y04106*
X02954Y04096*
X02953Y04086*
X02954Y04075*
X02959Y04065*
X02965Y04056*
X02974Y0405*
X02984Y04046*
X02994Y04044*
X03005Y04046*
X03015Y0405*
X03024Y04056*
X0303Y04065*
X03034Y04075*
X03036Y04086*
X03034Y04096*
X0303Y04106*
X03024Y04115*
X03015Y04121*
X03005Y04126*
X02994Y04127*
G37*
G36*
X069Y0416D02*
X06887Y04159D01*
X06874Y04155*
X06862Y04149*
X06852Y04141*
X06844Y0413*
X06837Y04119*
X06834Y04106*
X06832Y04093*
X06834Y0408*
X06837Y04067*
X06844Y04056*
X06852Y04045*
X06862Y04037*
X06874Y04031*
X06887Y04027*
X069Y04026*
X06913Y04027*
X06925Y04031*
X06937Y04037*
X06947Y04045*
X06956Y04056*
X06962Y04067*
X06966Y0408*
X06967Y04093*
X06966Y04106*
X06962Y04119*
X06956Y0413*
X06947Y04141*
X06937Y04149*
X06925Y04155*
X06913Y04159*
X069Y0416*
G37*
G36*
X06569D02*
X06556Y04159D01*
X06543Y04155*
X06532Y04149*
X06521Y04141*
X06513Y0413*
X06507Y04119*
X06503Y04106*
X06502Y04093*
X06503Y0408*
X06507Y04067*
X06513Y04056*
X06521Y04045*
X06532Y04037*
X06543Y04031*
X06556Y04027*
X06569Y04026*
X06582Y04027*
X06595Y04031*
X06606Y04037*
X06617Y04045*
X06625Y04056*
X06631Y04067*
X06635Y0408*
X06636Y04093*
X06635Y04106*
X06631Y04119*
X06625Y0413*
X06617Y04141*
X06606Y04149*
X06595Y04155*
X06582Y04159*
X06569Y0416*
G37*
G36*
X02043Y04093D02*
X02034Y04092D01*
X02025Y04088*
X02017Y04083*
X02012Y04075*
X02008Y04067*
X02007Y04057*
X02008Y04048*
X02012Y04039*
X02017Y04032*
X02025Y04026*
X02034Y04023*
X02043Y04022*
X02052Y04023*
X02061Y04026*
X02068Y04032*
X02074Y04039*
X02077Y04048*
X02079Y04057*
X02077Y04067*
X02074Y04075*
X02068Y04083*
X02061Y04088*
X02052Y04092*
X02043Y04093*
G37*
G36*
X00285Y04285D02*
X00264Y04283D01*
X00244Y04278*
X00224Y0427*
X00207Y04259*
X00191Y04246*
X00177Y0423*
X00166Y04212*
X00158Y04193*
X00153Y04172*
X00152Y04152*
X00153Y04131*
X00158Y0411*
X00166Y04091*
X00177Y04073*
X00191Y04057*
X00207Y04044*
X00224Y04033*
X00244Y04025*
X00264Y0402*
X00285Y04018*
X00306Y0402*
X00326Y04025*
X00346Y04033*
X00363Y04044*
X00379Y04057*
X00393Y04073*
X00404Y04091*
X00412Y0411*
X00417Y04131*
X00418Y04152*
X00417Y04172*
X00412Y04193*
X00404Y04212*
X00393Y0423*
X00379Y04246*
X00363Y04259*
X00346Y0427*
X00326Y04278*
X00306Y04283*
X00285Y04285*
G37*
G36*
X01457Y04089D02*
X01448Y04088D01*
X01439Y04084*
X01432Y04079*
X01426Y04071*
X01423Y04063*
X01421Y04053*
X01423Y04044*
X01426Y04036*
X01432Y04028*
X01439Y04022*
X01448Y04019*
X01457Y04018*
X01466Y04019*
X01475Y04022*
X01483Y04028*
X01488Y04036*
X01492Y04044*
X01493Y04053*
X01492Y04063*
X01488Y04071*
X01483Y04079*
X01475Y04084*
X01466Y04088*
X01457Y04089*
G37*
G36*
X01903Y04034D02*
X01897Y04033D01*
X01892Y04029*
X01888Y04024*
X01887Y04018*
X01888Y04011*
X01892Y04006*
X01897Y04002*
X01903Y04001*
X0191Y04002*
X01915Y04006*
X01918Y04011*
X0192Y04018*
X01918Y04024*
X01915Y04029*
X0191Y04033*
X01903Y04034*
G37*
G36*
X02353Y04034D02*
X02347Y04032D01*
X02341Y04029*
X02338Y04023*
X02337Y04017*
X02338Y04011*
X02341Y04006*
X02347Y04002*
X02353Y04001*
X02359Y04002*
X02364Y04006*
X02368Y04011*
X02369Y04017*
X02368Y04023*
X02364Y04029*
X02359Y04032*
X02353Y04034*
G37*
G36*
X05723Y04083D02*
X05708Y04081D01*
X05694Y04075*
X05682Y04066*
X05673Y04054*
X05667Y0404*
X05665Y04025*
X05667Y0401*
X05673Y03996*
X05682Y03984*
X05694Y03975*
X05708Y03969*
X05723Y03967*
X05738Y03969*
X05752Y03975*
X05764Y03984*
X05773Y03996*
X05779Y0401*
X05781Y04025*
X05779Y0404*
X05773Y04054*
X05764Y04066*
X05752Y04075*
X05738Y04081*
X05723Y04083*
G37*
G36*
X01408Y03996D02*
X01402Y03995D01*
X01396Y03991*
X01393Y03986*
X01392Y0398*
X01393Y03974*
X01396Y03968*
X01402Y03965*
X01408Y03964*
X01414Y03965*
X0142Y03968*
X01423Y03974*
X01424Y0398*
X01423Y03986*
X0142Y03991*
X01414Y03995*
X01408Y03996*
G37*
G36*
X02084Y03912D02*
X02078Y03911D01*
X02073Y03907*
X02069Y03902*
X02068Y03896*
X02069Y03889*
X02069Y03889*
X02066Y03885*
X02066Y03886*
X02059Y03887*
X02053Y03886*
X02048Y03882*
X02044Y03877*
X02043Y03871*
X02044Y03864*
X02048Y03859*
X02053Y03855*
X02059Y03854*
X02066Y03855*
X02071Y03859*
X02074Y03864*
X02076Y03871*
X02074Y03877*
X02074Y03877*
X02078Y03881*
X02078Y0388*
X02084Y03879*
X02091Y0388*
X02096Y03884*
X02099Y03889*
X02101Y03896*
X02099Y03902*
X02096Y03907*
X02091Y03911*
X02084Y03912*
G37*
G36*
X02029Y03852D02*
X02023Y03851D01*
X02018Y03847*
X02014Y03842*
X02013Y03836*
X02013Y03835*
X02013Y03834*
X02009Y03831*
X02004Y03832*
X01998Y03831*
X01993Y03827*
X01989Y03822*
X01988Y03816*
X01989Y03809*
X01993Y03804*
X01998Y038*
X02004Y03799*
X02011Y038*
X02016Y03804*
X02019Y03809*
X02021Y03816*
X02021Y03816*
X02021Y03817*
X02025Y0382*
X02029Y03819*
X02036Y0382*
X02041Y03824*
X02044Y03829*
X02046Y03836*
X02044Y03842*
X02041Y03847*
X02036Y03851*
X02029Y03852*
G37*
G36*
X03699D02*
X03693Y03851D01*
X03688Y03847*
X03684Y03842*
X03683Y03836*
X03684Y03829*
X03688Y03824*
X03693Y0382*
X03699Y03819*
X03706Y0382*
X03711Y03824*
X03714Y03829*
X03716Y03836*
X03714Y03842*
X03711Y03847*
X03706Y03851*
X03699Y03852*
G37*
G36*
X03014Y03847D02*
X03008Y03846D01*
X03003Y03842*
X02999Y03837*
X02998Y03831*
X02999Y03824*
X03003Y03819*
X03008Y03815*
X03014Y03814*
X03021Y03815*
X03026Y03819*
X03029Y03824*
X03031Y03831*
X03029Y03837*
X03026Y03842*
X03021Y03846*
X03014Y03847*
G37*
G36*
X03829Y03822D02*
X03823Y03821D01*
X03818Y03817*
X03814Y03812*
X03813Y03806*
X03814Y03799*
X03818Y03794*
X03823Y0379*
X03829Y03789*
X03836Y0379*
X03841Y03794*
X03844Y03799*
X03846Y03806*
X03844Y03812*
X03841Y03817*
X03836Y03821*
X03829Y03822*
G37*
G36*
X03539D02*
X03533Y03821D01*
X03528Y03817*
X03524Y03812*
X03523Y03806*
X03524Y03799*
X03528Y03794*
X03533Y0379*
X03539Y03789*
X03546Y0379*
X03551Y03794*
X03554Y03799*
X03556Y03806*
X03554Y03812*
X03551Y03817*
X03546Y03821*
X03539Y03822*
G37*
G36*
X03219D02*
X03213Y03821D01*
X03208Y03817*
X03204Y03812*
X03203Y03806*
X03204Y03799*
X03208Y03794*
X03213Y0379*
X03219Y03789*
X03226Y0379*
X03231Y03794*
X03234Y03799*
X03236Y03806*
X03234Y03812*
X03231Y03817*
X03226Y03821*
X03219Y03822*
G37*
G36*
X05723Y03902D02*
X05708Y039D01*
X05694Y03894*
X05682Y03885*
X05673Y03873*
X05667Y03859*
X05665Y03844*
X05667Y03829*
X05673Y03815*
X05682Y03803*
X05694Y03794*
X05708Y03788*
X05723Y03786*
X05738Y03788*
X05752Y03794*
X05764Y03803*
X05773Y03815*
X05779Y03829*
X05781Y03844*
X05779Y03859*
X05773Y03873*
X05764Y03885*
X05752Y03894*
X05738Y039*
X05723Y03902*
G37*
G36*
X02722Y03802D02*
X02716Y03801D01*
X0271Y03797*
X02707Y03792*
X02706Y03786*
X02707Y03779*
X0271Y03774*
X02716Y03771*
X02722Y03769*
X02728Y03771*
X02733Y03774*
X02737Y03779*
X02738Y03786*
X02737Y03792*
X02733Y03797*
X02728Y03801*
X02722Y03802*
G37*
G36*
X06169Y03877D02*
X0607D01*
X06055Y03875*
X06041Y03869*
X06029Y0386*
X0602Y03848*
X06014Y03834*
X06012Y03819*
X06014Y03804*
X0602Y0379*
X06029Y03779*
X06041Y03769*
X06055Y03764*
X0607Y03762*
X06169*
X06183Y03764*
X06197Y03769*
X06209Y03779*
X06219Y0379*
X06224Y03804*
X06226Y03819*
X06224Y03834*
X06219Y03848*
X06209Y0386*
X06197Y03869*
X06183Y03875*
X06169Y03877*
G37*
G36*
X04254Y03792D02*
X04248Y03791D01*
X04243Y03787*
X04239Y03782*
X04238Y03776*
X04239Y03769*
X04243Y03764*
X04248Y0376*
X04254Y03759*
X04261Y0376*
X04266Y03764*
X04269Y03769*
X04271Y03776*
X04269Y03782*
X04266Y03787*
X04261Y03791*
X04254Y03792*
G37*
G36*
X069Y03863D02*
X06885Y03861D01*
X06871Y03856*
X06859Y03846*
X0685Y03834*
X06844Y03821*
X06842Y03806*
X06844Y03791*
X0685Y03777*
X06859Y03765*
X06871Y03756*
X06885Y0375*
X069Y03748*
X06915Y0375*
X06929Y03756*
X06941Y03765*
X0695Y03777*
X06955Y03791*
X06957Y03806*
X06955Y03821*
X0695Y03834*
X06941Y03846*
X06929Y03856*
X06915Y03861*
X069Y03863*
G37*
G36*
X06734D02*
X06719Y03861D01*
X06705Y03856*
X06694Y03846*
X06684Y03834*
X06679Y03821*
X06677Y03806*
X06679Y03791*
X06684Y03777*
X06694Y03765*
X06705Y03756*
X06719Y0375*
X06734Y03748*
X06749Y0375*
X06763Y03756*
X06775Y03765*
X06784Y03777*
X0679Y03791*
X06792Y03806*
X0679Y03821*
X06784Y03834*
X06775Y03846*
X06763Y03856*
X06749Y03861*
X06734Y03863*
G37*
G36*
X06569D02*
X06554Y03861D01*
X0654Y03856*
X06528Y03846*
X06519Y03834*
X06513Y03821*
X06511Y03806*
X06513Y03791*
X06519Y03777*
X06528Y03765*
X0654Y03756*
X06554Y0375*
X06569Y03748*
X06584Y0375*
X06598Y03756*
X0661Y03765*
X06619Y03777*
X06625Y03791*
X06627Y03806*
X06625Y03821*
X06619Y03834*
X0661Y03846*
X06598Y03856*
X06584Y03861*
X06569Y03863*
G37*
G36*
X03699Y03767D02*
X03693Y03766D01*
X03688Y03762*
X03684Y03757*
X03683Y03751*
X03684Y03744*
X03688Y03739*
X03693Y03735*
X03699Y03734*
X03706Y03735*
X03711Y03739*
X03714Y03744*
X03716Y03751*
X03714Y03757*
X03711Y03762*
X03706Y03766*
X03699Y03767*
G37*
G36*
X02993D02*
X02987Y03766D01*
X02981Y03762*
X02978Y03757*
X02977Y03751*
X02978Y03744*
X02981Y03739*
X02987Y03735*
X02993Y03734*
X02999Y03735*
X03004Y03739*
X03008Y03744*
X03009Y03751*
X03008Y03757*
X03004Y03762*
X02999Y03766*
X02993Y03767*
G37*
G36*
X06294Y03717D02*
X06288Y03716D01*
X06283Y03712*
X06279Y03707*
X06278Y03701*
X06279Y03694*
X06283Y03689*
X06288Y03685*
X06294Y03684*
X06301Y03685*
X06306Y03689*
X06309Y03694*
X06311Y03701*
X06309Y03707*
X06306Y03712*
X06301Y03716*
X06294Y03717*
G37*
G36*
X01849D02*
X01843Y03716D01*
X01838Y03712*
X01834Y03707*
X01833Y03701*
X01834Y03694*
X01838Y03689*
X01843Y03685*
X01849Y03684*
X01856Y03685*
X01861Y03689*
X01864Y03694*
X01866Y03701*
X01864Y03707*
X01861Y03712*
X01856Y03716*
X01849Y03717*
G37*
G36*
X04049Y03681D02*
X04043Y0368D01*
X04038Y03676*
X04034Y03671*
X04033Y03665*
X04034Y03658*
X04038Y03653*
X04043Y03649*
X04049Y03648*
X04056Y03649*
X04061Y03653*
X04064Y03658*
X04066Y03665*
X04064Y03671*
X04061Y03676*
X04056Y0368*
X04049Y03681*
G37*
G36*
X02679Y03677D02*
X02673Y03676D01*
X02668Y03672*
X02664Y03667*
X02663Y03661*
X02664Y03654*
X02668Y03649*
X02673Y03645*
X02679Y03644*
X02686Y03645*
X02691Y03649*
X02694Y03654*
X02696Y03661*
X02694Y03667*
X02691Y03672*
X02686Y03676*
X02679Y03677*
G37*
G36*
X01754D02*
X01748Y03676D01*
X01743Y03672*
X01739Y03667*
X01738Y03661*
X01739Y03654*
X01743Y03649*
X01748Y03645*
X01754Y03644*
X01761Y03645*
X01766Y03649*
X01769Y03654*
X01771Y03661*
X01769Y03667*
X01766Y03672*
X01761Y03676*
X01754Y03677*
G37*
G36*
X03424Y03652D02*
X03418Y03651D01*
X03413Y03647*
X03409Y03642*
X03408Y03636*
X03409Y03629*
X03413Y03624*
X03418Y0362*
X03424Y03619*
X03431Y0362*
X03436Y03624*
X03439Y03629*
X03441Y03636*
X03439Y03642*
X03436Y03647*
X03431Y03651*
X03424Y03652*
G37*
G36*
X02799Y03632D02*
X02793Y03631D01*
X02788Y03627*
X02784Y03622*
X02783Y03616*
X02784Y03609*
X02788Y03604*
X02793Y036*
X02799Y03599*
X02806Y036*
X02811Y03604*
X02814Y03609*
X02816Y03616*
X02814Y03622*
X02811Y03627*
X02806Y03631*
X02799Y03632*
G37*
G36*
X02139Y03627D02*
X02133Y03626D01*
X02128Y03622*
X02124Y03617*
X02123Y03611*
X02124Y03604*
X02128Y03599*
X02133Y03595*
X02139Y03594*
X02146Y03595*
X02151Y03599*
X02154Y03604*
X02156Y03611*
X02154Y03617*
X02151Y03622*
X02146Y03626*
X02139Y03627*
G37*
G36*
X01884Y03617D02*
X01878Y03616D01*
X01873Y03612*
X01869Y03607*
X01868Y03601*
X01869Y03594*
X01873Y03589*
X01878Y03585*
X01884Y03584*
X01891Y03585*
X01896Y03589*
X01899Y03594*
X01901Y03601*
X01899Y03607*
X01896Y03612*
X01891Y03616*
X01884Y03617*
G37*
G36*
X03239Y03612D02*
X03233Y03611D01*
X03228Y03607*
X03224Y03602*
X03223Y03596*
X03224Y03589*
X03228Y03584*
X03233Y0358*
X03239Y03579*
X03246Y0358*
X03251Y03584*
X03254Y03589*
X03256Y03596*
X03254Y03602*
X03251Y03607*
X03246Y03611*
X03239Y03612*
G37*
G36*
X01549Y03637D02*
X01543Y03636D01*
X01538Y03632*
X01534Y03627*
X01533Y03621*
X01534Y03614*
X01538Y03609*
X01543Y03605*
X01549Y03604*
X01556Y03605*
X01556Y03606*
X01559Y03602*
X01559Y03602*
X01558Y03596*
X01559Y03589*
X01563Y03584*
X01568Y0358*
X01574Y03579*
X01581Y0358*
X01586Y03584*
X01589Y03589*
X01591Y03596*
X01589Y03602*
X01586Y03607*
X01581Y03611*
X01574Y03612*
X01568Y03611*
X01568Y0361*
X01564Y03614*
X01564Y03614*
X01566Y03621*
X01564Y03627*
X01561Y03632*
X01556Y03636*
X01549Y03637*
G37*
G36*
X02422Y03624D02*
X02413Y03623D01*
X02405Y03617*
X024Y0361*
X02398Y03601*
X024Y03592*
X02405Y03584*
X02413Y03579*
X02422Y03577*
X02431Y03579*
X02438Y03584*
X02443Y03592*
X02445Y03601*
X02443Y0361*
X02438Y03617*
X02431Y03623*
X02422Y03624*
G37*
G36*
X02774Y03582D02*
X02768Y03581D01*
X02763Y03577*
X02759Y03572*
X02758Y03566*
X02759Y03559*
X02763Y03554*
X02768Y0355*
X02774Y03549*
X02781Y0355*
X02786Y03554*
X02789Y03559*
X02791Y03566*
X02789Y03572*
X02786Y03577*
X02781Y03581*
X02774Y03582*
G37*
G36*
X0144Y03573D02*
X01434Y03572D01*
X01429Y03568*
X01425Y03563*
X01424Y03557*
X01425Y0355*
X01429Y03545*
X01434Y03541*
X0144Y0354*
X01447Y03541*
X01452Y03545*
X01455Y0355*
X01457Y03557*
X01455Y03563*
X01452Y03568*
X01447Y03572*
X0144Y03573*
G37*
G36*
X05994Y03568D02*
X05988Y03567D01*
X05983Y03563*
X05979Y03558*
X05978Y03552*
X05979Y03545*
X05983Y0354*
X05988Y03536*
X05994Y03535*
X06001Y03536*
X06006Y0354*
X06009Y03545*
X06011Y03552*
X06009Y03558*
X06006Y03563*
X06001Y03567*
X05994Y03568*
G37*
G36*
X02434Y03562D02*
X02428Y03561D01*
X02423Y03557*
X02419Y03552*
X02418Y03546*
X02419Y03539*
X02423Y03534*
X02428Y0353*
X02434Y03529*
X02441Y0353*
X02446Y03534*
X02449Y03539*
X02451Y03546*
X02449Y03552*
X02446Y03557*
X02441Y03561*
X02434Y03562*
G37*
G36*
X02254Y03552D02*
X02248Y03551D01*
X02243Y03547*
X02239Y03542*
X02238Y03536*
X02239Y03529*
X02242Y03525*
X02239Y03521*
X02234Y03522*
X02228Y03521*
X02223Y03517*
X02219Y03512*
X02218Y03506*
X02219Y03499*
X02223Y03494*
X02228Y0349*
X02234Y03489*
X02241Y0349*
X02246Y03494*
X02249Y03499*
X02251Y03506*
X02249Y03512*
X02247Y03516*
X0225Y0352*
X02254Y03519*
X02261Y0352*
X02266Y03524*
X02269Y03529*
X02271Y03536*
X02269Y03542*
X02266Y03547*
X02261Y03551*
X02254Y03552*
G37*
G36*
X05274Y03527D02*
X05268Y03526D01*
X05263Y03522*
X05259Y03517*
X05258Y03511*
X05259Y03504*
X05263Y03499*
X05268Y03495*
X05274Y03494*
X05281Y03495*
X05286Y03499*
X05289Y03504*
X05291Y03511*
X05289Y03517*
X05286Y03522*
X05281Y03526*
X05274Y03527*
G37*
G36*
X03622Y03502D02*
X03616Y03501D01*
X03611Y03497*
X03607Y03492*
X03606Y03486*
X03607Y03479*
X03611Y03474*
X03616Y0347*
X03622Y03469*
X03629Y0347*
X03634Y03474*
X03637Y03479*
X03639Y03486*
X03637Y03492*
X03634Y03497*
X03629Y03501*
X03622Y03502*
G37*
G36*
X02579D02*
X02573Y03501D01*
X02568Y03497*
X02564Y03492*
X02563Y03486*
X02564Y03479*
X02568Y03474*
X02573Y0347*
X02579Y03469*
X02586Y0347*
X02591Y03474*
X02594Y03479*
X02596Y03486*
X02594Y03492*
X02591Y03497*
X02586Y03501*
X02579Y03502*
G37*
G36*
X03529Y03497D02*
X03523Y03496D01*
X03518Y03492*
X03514Y03487*
X03513Y03481*
X03514Y03474*
X03518Y03469*
X03523Y03465*
X03529Y03464*
X03536Y03465*
X03541Y03469*
X03544Y03474*
X03546Y03481*
X03544Y03487*
X03541Y03492*
X03536Y03496*
X03529Y03497*
G37*
G36*
X02389D02*
X02383Y03496D01*
X02378Y03492*
X02374Y03487*
X02373Y03481*
X02374Y03474*
X02378Y03469*
X02383Y03465*
X02389Y03464*
X02396Y03465*
X02401Y03469*
X02404Y03474*
X02406Y03481*
X02404Y03487*
X02401Y03492*
X02396Y03496*
X02389Y03497*
G37*
G36*
X06509Y03472D02*
X06503Y03471D01*
X06498Y03467*
X06494Y03462*
X06493Y03456*
X06494Y03449*
X06498Y03444*
X06503Y0344*
X06509Y03439*
X06516Y0344*
X06521Y03444*
X06524Y03449*
X06526Y03456*
X06524Y03462*
X06521Y03467*
X06516Y03471*
X06509Y03472*
G37*
G36*
X03436Y03473D02*
X0343Y03472D01*
X03425Y03468*
X03421Y03463*
X0342Y03457*
X03421Y0345*
X03425Y03445*
X0343Y03441*
X03436Y0344*
X03443Y03441*
X03448Y03445*
X0345Y03448*
X0345Y03448*
X03456Y03447*
X03458Y03444*
X03463Y0344*
X03469Y03439*
X03476Y0344*
X03481Y03444*
X03484Y03449*
X03486Y03456*
X03484Y03462*
X03481Y03467*
X03476Y03471*
X03469Y03472*
X03463Y03471*
X03458Y03467*
X03456Y03464*
X03456Y03464*
X0345Y03465*
X03448Y03468*
X03443Y03472*
X03436Y03473*
G37*
G36*
X03358Y03464D02*
X03352Y03463D01*
X03347Y03459*
X03343Y03454*
X03342Y03448*
X03343Y03441*
X03347Y03436*
X03352Y03432*
X03358Y03431*
X03365Y03432*
X0337Y03436*
X03373Y03441*
X03374Y03443*
X03379*
X03379Y0344*
X03383Y03435*
X03388Y03431*
X03394Y0343*
X03401Y03431*
X03406Y03435*
X03409Y0344*
X03411Y03447*
X03409Y03453*
X03406Y03458*
X03401Y03462*
X03394Y03463*
X03388Y03462*
X03383Y03458*
X03379Y03453*
X03379Y03451*
X03374*
X03373Y03454*
X0337Y03459*
X03365Y03463*
X03358Y03464*
G37*
G36*
X02422Y03467D02*
X02413Y03465D01*
X02405Y0346*
X024Y03452*
X02398Y03443*
X024Y03434*
X02405Y03427*
X02413Y03422*
X02422Y0342*
X02431Y03422*
X02438Y03427*
X02443Y03434*
X02445Y03443*
X02443Y03452*
X02438Y0346*
X02431Y03465*
X02422Y03467*
G37*
G36*
X06479Y03442D02*
X06473Y03441D01*
X06468Y03437*
X06464Y03432*
X06463Y03426*
X06464Y03419*
X06468Y03414*
X06473Y0341*
X06479Y03409*
X06486Y0341*
X06491Y03414*
X06494Y03419*
X06496Y03426*
X06494Y03432*
X06491Y03437*
X06486Y03441*
X06479Y03442*
G37*
G36*
X02634Y03422D02*
X02628Y03421D01*
X02623Y03417*
X02619Y03412*
X02618Y03406*
X02619Y03399*
X02623Y03394*
X02628Y0339*
X02634Y03389*
X02641Y0339*
X02646Y03394*
X02649Y03399*
X02651Y03406*
X02649Y03412*
X02646Y03417*
X02641Y03421*
X02634Y03422*
G37*
G36*
X06447Y03412D02*
X06441Y03411D01*
X06436Y03407*
X06432Y03402*
X06431Y03396*
X06432Y03389*
X06436Y03384*
X06441Y0338*
X06447Y03379*
X06453Y0338*
X06459Y03384*
X06462Y03389*
X06463Y03396*
X06462Y03402*
X06459Y03407*
X06453Y03411*
X06447Y03412*
G37*
G36*
X03068Y03411D02*
X03062Y0341D01*
X03057Y03407*
X03053Y03401*
X03052Y03395*
X03053Y03389*
X03057Y03384*
X03062Y0338*
X03068Y03379*
X03075Y0338*
X0308Y03384*
X03083Y03389*
X03085Y03395*
X03083Y03401*
X0308Y03407*
X03075Y0341*
X03068Y03411*
G37*
G36*
X06409Y03387D02*
X06403Y03386D01*
X06398Y03382*
X06394Y03377*
X06393Y03371*
X06394Y03364*
X06398Y03359*
X06403Y03355*
X06409Y03354*
X06416Y03355*
X06421Y03359*
X06424Y03364*
X06426Y03371*
X06424Y03377*
X06421Y03382*
X06416Y03386*
X06409Y03387*
G37*
G36*
X03302Y0336D02*
X03296Y03359D01*
X03291Y03355*
X03287Y0335*
X03286Y03344*
X03287Y03337*
X03291Y03332*
X03296Y03328*
X03302Y03327*
X03309Y03328*
X03314Y03332*
X03317Y03337*
X03319Y03344*
X03317Y0335*
X03314Y03355*
X03309Y03359*
X03302Y0336*
G37*
G36*
X06354Y03347D02*
X06348Y03346D01*
X06343Y03342*
X06339Y03337*
X06338Y03331*
X06339Y03324*
X06343Y03319*
X06348Y03316*
X06354Y03314*
X0636Y03316*
X06366Y03319*
X06369Y03324*
X06371Y03331*
X06369Y03337*
X06366Y03342*
X0636Y03346*
X06354Y03347*
G37*
G36*
X03542Y03335D02*
X03536Y03334D01*
X03531Y0333*
X03527Y03325*
X03526Y03319*
X03527Y03312*
X03531Y03307*
X03536Y03303*
X03542Y03302*
X03549Y03303*
X03554Y03307*
X03557Y03312*
X03559Y03319*
X03557Y03325*
X03554Y0333*
X03549Y03334*
X03542Y03335*
G37*
G36*
X03263Y0332D02*
X03257Y03318D01*
X03252Y03315*
X03248Y0331*
X03247Y03303*
X03248Y03297*
X03252Y03292*
X03257Y03288*
X03263Y03287*
X03269Y03288*
X03275Y03292*
X03278Y03297*
X0328Y03303*
X03278Y0331*
X03275Y03315*
X03269Y03318*
X03263Y0332*
G37*
G36*
X03491Y03313D02*
X03485Y03312D01*
X0348Y03308*
X03476Y03303*
X03475Y03297*
X03476Y0329*
X0348Y03285*
X03485Y03281*
X03491Y0328*
X03498Y03281*
X03503Y03285*
X03506Y0329*
X03508Y03297*
X03506Y03303*
X03503Y03308*
X03498Y03312*
X03491Y03313*
G37*
G36*
X03653Y03309D02*
X03647Y03308D01*
X03642Y03304*
X03638Y03299*
X03637Y03293*
X03638Y03286*
X03642Y03281*
X03647Y03277*
X03653Y03276*
X0366Y03277*
X03665Y03281*
X03668Y03286*
X0367Y03293*
X03668Y03299*
X03665Y03304*
X0366Y03308*
X03653Y03309*
G37*
G36*
X06444Y03307D02*
X06438Y03306D01*
X06433Y03302*
X06429Y03297*
X06428Y03291*
X06429Y03284*
X06433Y03279*
X06438Y03275*
X06444Y03274*
X06451Y03275*
X06456Y03279*
X06459Y03284*
X06461Y03291*
X06459Y03297*
X06456Y03302*
X06451Y03306*
X06444Y03307*
G37*
G36*
X0259Y03304D02*
X02584Y03303D01*
X02579Y03299*
X02575Y03294*
X02574Y03288*
X02575Y03281*
X02579Y03276*
X02584Y03272*
X0259Y03271*
X02597Y03272*
X02602Y03276*
X02605Y03281*
X02607Y03288*
X02605Y03294*
X02602Y03299*
X02597Y03303*
X0259Y03304*
G37*
G36*
X03374Y03289D02*
X03368Y03288D01*
X03363Y03284*
X03359Y03279*
X03358Y03273*
X03359Y03266*
X03363Y03261*
X03368Y03257*
X03374Y03256*
X03381Y03257*
X03386Y03261*
X03389Y03266*
X03391Y03273*
X03389Y03279*
X03386Y03284*
X03381Y03288*
X03374Y03289*
G37*
G36*
X06334Y03282D02*
X06328Y03281D01*
X06323Y03277*
X06319Y03272*
X06318Y03266*
X06319Y03259*
X06323Y03254*
X06328Y0325*
X06334Y03249*
X06341Y0325*
X06346Y03254*
X06349Y03259*
X06351Y03266*
X06349Y03272*
X06346Y03277*
X06341Y03281*
X06334Y03282*
G37*
G36*
X03744Y03277D02*
X03738Y03276D01*
X03733Y03272*
X03729Y03267*
X03728Y03261*
X03729Y03254*
X03733Y03249*
X03738Y03245*
X03744Y03244*
X03751Y03245*
X03756Y03249*
X03759Y03254*
X03761Y03261*
X03759Y03267*
X03756Y03272*
X03751Y03276*
X03744Y03277*
G37*
G36*
X02259D02*
X02253Y03276D01*
X02248Y03272*
X02244Y03267*
X02243Y03261*
X02244Y03254*
X02248Y03249*
X02253Y03245*
X02259Y03244*
X02266Y03245*
X02271Y03249*
X02274Y03254*
X02276Y03261*
X02274Y03267*
X02271Y03272*
X02266Y03276*
X02259Y03277*
G37*
G36*
X0323Y03251D02*
X03224Y0325D01*
X03219Y03246*
X03215Y03241*
X03214Y03235*
X03215Y03228*
X03219Y03223*
X03224Y03219*
X0323Y03218*
X03237Y03219*
X03242Y03223*
X03245Y03228*
X03247Y03235*
X03245Y03241*
X03242Y03246*
X03237Y0325*
X0323Y03251*
G37*
G36*
X06282Y03242D02*
X06276Y03241D01*
X0627Y03237*
X06267Y03232*
X06266Y03226*
X06267Y03219*
X0627Y03214*
X06276Y0321*
X06282Y03209*
X06288Y0321*
X06293Y03214*
X06297Y03219*
X06298Y03226*
X06297Y03232*
X06293Y03237*
X06288Y03241*
X06282Y03242*
G37*
G36*
X03806Y03251D02*
X038Y0325D01*
X03795Y03246*
X03791Y03241*
X0379Y03235*
X03791Y03228*
X03795Y03223*
X03797Y03222*
X03796Y03216*
X03793Y03216*
X03788Y03212*
X03784Y03207*
X03783Y03201*
X03784Y03194*
X03788Y03189*
X03793Y03185*
X03799Y03184*
X03806Y03185*
X03811Y03189*
X03814Y03194*
X03816Y03201*
X03814Y03207*
X03811Y03212*
X03809Y03214*
X0381Y03219*
X03813Y03219*
X03818Y03223*
X03821Y03228*
X03823Y03235*
X03821Y03241*
X03818Y03246*
X03813Y0325*
X03806Y03251*
G37*
G36*
X02205Y03216D02*
X02199Y03215D01*
X02194Y03211*
X0219Y03206*
X02189Y032*
X0219Y03193*
X02194Y03188*
X02199Y03184*
X02205Y03183*
X02212Y03184*
X02217Y03188*
X0222Y03193*
X02222Y032*
X0222Y03206*
X02217Y03211*
X02212Y03215*
X02205Y03216*
G37*
G36*
X02422Y03263D02*
X02413Y03261D01*
X02405Y03256*
X024Y03248*
X02398Y03239*
X024Y0323*
X02405Y03223*
X02409Y0322*
X02408Y03215*
X02407Y03214*
X02402Y03211*
X02398Y03206*
X02397Y03199*
X02398Y03193*
X02402Y03188*
X02407Y03184*
X02414Y03183*
X0242Y03184*
X02425Y03188*
X02429Y03193*
X0243Y03199*
X02429Y03206*
X02425Y03211*
X02425Y03211*
X02426Y03217*
X02431Y03218*
X02438Y03223*
X02443Y0323*
X02445Y03239*
X02443Y03248*
X02438Y03256*
X02431Y03261*
X02422Y03263*
G37*
G36*
X06309Y03215D02*
X06303Y03214D01*
X06297Y0321*
X06294Y03205*
X06293Y03199*
X06294Y03192*
X06297Y03187*
X06303Y03183*
X06309Y03182*
X06315Y03183*
X0632Y03187*
X06324Y03192*
X06325Y03199*
X06324Y03205*
X0632Y0321*
X06315Y03214*
X06309Y03215*
G37*
G36*
X06439Y03207D02*
X06433Y03206D01*
X06428Y03202*
X06424Y03197*
X06423Y03191*
X06424Y03184*
X06428Y03179*
X06433Y03175*
X06439Y03174*
X06446Y03175*
X06451Y03179*
X06454Y03184*
X06456Y03191*
X06454Y03197*
X06451Y03202*
X06446Y03206*
X06439Y03207*
G37*
G36*
X03188Y03203D02*
X03182Y03202D01*
X03177Y03198*
X03173Y03193*
X03172Y03187*
X03173Y0318*
X03177Y03175*
X03182Y03171*
X03188Y0317*
X03195Y03171*
X032Y03175*
X03204Y0318*
X03205Y03187*
X03204Y03193*
X032Y03198*
X03195Y03202*
X03188Y03203*
G37*
G36*
X02591Y03202D02*
X02585Y03201D01*
X0258Y03197*
X02576Y03192*
X02575Y03186*
X02576Y03179*
X0258Y03174*
X02585Y03171*
X02591Y03169*
X02598Y03171*
X02603Y03174*
X02606Y03179*
X02608Y03186*
X02606Y03192*
X02603Y03197*
X02598Y03201*
X02591Y03202*
G37*
G36*
X02462Y03188D02*
X02456Y03187D01*
X0245Y03183*
X02447Y03178*
X02446Y03172*
X02447Y03166*
X0245Y0316*
X02456Y03157*
X02462Y03155*
X02468Y03157*
X02473Y0316*
X02477Y03166*
X02478Y03172*
X02477Y03178*
X02473Y03183*
X02468Y03187*
X02462Y03188*
G37*
G36*
X06339Y03167D02*
X06333Y03166D01*
X06328Y03162*
X06324Y03157*
X06323Y03151*
X06324Y03144*
X06328Y03139*
X06333Y03135*
X06339Y03134*
X06346Y03135*
X06351Y03139*
X06354Y03144*
X06356Y03151*
X06354Y03157*
X06351Y03162*
X06346Y03166*
X06339Y03167*
G37*
G36*
X03829Y03192D02*
X03823Y03191D01*
X03818Y03187*
X03814Y03182*
X03813Y03176*
X03814Y03169*
X03818Y03164*
X03823Y0316*
X03829Y03159*
X03836Y0316*
X03836Y03161*
X03839Y03157*
X03839Y03157*
X03838Y03151*
X03839Y03144*
X03843Y03139*
X03848Y03135*
X03854Y03134*
X03861Y03135*
X03866Y03139*
X03869Y03144*
X03871Y03151*
X03869Y03157*
X03866Y03162*
X03861Y03166*
X03854Y03167*
X03848Y03166*
X03848Y03165*
X03844Y03169*
X03844Y03169*
X03846Y03176*
X03844Y03182*
X03841Y03187*
X03836Y03191*
X03829Y03192*
G37*
G36*
X01459Y03163D02*
X01453Y03162D01*
X01448Y03158*
X01444Y03153*
X01443Y03147*
X01444Y0314*
X01448Y03135*
X01453Y03131*
X01459Y0313*
X01466Y03131*
X01471Y03135*
X01474Y0314*
X01476Y03147*
X01474Y03153*
X01471Y03158*
X01466Y03162*
X01459Y03163*
G37*
G36*
X03275Y03158D02*
X03269Y03156D01*
X03264Y03153*
X0326Y03147*
X03259Y03141*
X0326Y03135*
X03264Y0313*
X03269Y03126*
X03275Y03125*
X03281Y03126*
X03287Y0313*
X0329Y03135*
X03291Y03141*
X0329Y03147*
X03287Y03153*
X03281Y03156*
X03275Y03158*
G37*
G36*
X06304Y03137D02*
X06298Y03136D01*
X06293Y03132*
X06289Y03127*
X06288Y03121*
X06289Y03114*
X06293Y03109*
X06298Y03105*
X06304Y03104*
X06311Y03105*
X06316Y03109*
X06319Y03114*
X06321Y03121*
X06319Y03127*
X06316Y03132*
X06311Y03136*
X06304Y03137*
G37*
G36*
X03939D02*
X03933Y03136D01*
X03928Y03132*
X03924Y03127*
X03923Y03121*
X03924Y03114*
X03928Y03109*
X03933Y03105*
X03939Y03104*
X03946Y03105*
X03951Y03109*
X03954Y03114*
X03956Y03121*
X03954Y03127*
X03951Y03132*
X03946Y03136*
X03939Y03137*
G37*
G36*
X03491Y03119D02*
X03485Y03118D01*
X0348Y03114*
X03476Y03109*
X03475Y03103*
X03476Y03096*
X0348Y03091*
X03485Y03087*
X03491Y03086*
X03498Y03087*
X03503Y03091*
X03506Y03096*
X03508Y03103*
X03506Y03109*
X03503Y03114*
X03498Y03118*
X03491Y03119*
G37*
G36*
X02418Y03134D02*
X02412Y03133D01*
X02407Y0313*
X02403Y03124*
X02402Y03118*
X02403Y03112*
X02407Y03106*
X02408Y03106*
Y031*
X02405Y03098*
X024Y03091*
X02398Y03082*
X024Y03073*
X02405Y03065*
X02413Y0306*
X02422Y03058*
X02431Y0306*
X02438Y03065*
X02443Y03073*
X02445Y03082*
X02443Y03091*
X02438Y03098*
X02432Y03102*
X02431Y03105*
X02431Y03108*
X02433Y03112*
X02435Y03118*
X02433Y03124*
X0243Y0313*
X02424Y03133*
X02418Y03134*
G37*
G36*
X03368Y03066D02*
X03362Y03065D01*
X03357Y03061*
X03353Y03056*
X03352Y0305*
X03353Y03043*
X03357Y03038*
X03362Y03034*
X03368Y03033*
X03375Y03034*
X0338Y03038*
X03383Y03043*
X03385Y0305*
X03383Y03056*
X0338Y03061*
X03375Y03065*
X03368Y03066*
G37*
G36*
X03344Y03012D02*
X03338Y03011D01*
X03333Y03007*
X03329Y03002*
X03328Y02996*
X03329Y02989*
X03333Y02984*
X03338Y0298*
X03344Y02979*
X03351Y0298*
X03356Y02984*
X03359Y02989*
X03361Y02996*
X03359Y03002*
X03356Y03007*
X03351Y03011*
X03344Y03012*
G37*
G36*
X03197Y02986D02*
X03191Y02985D01*
X03186Y02981*
X03182Y02976*
X03181Y0297*
X03182Y02963*
X03186Y02958*
X03191Y02954*
X03197Y02953*
X03204Y02954*
X03209Y02958*
X03212Y02963*
X03214Y0297*
X03212Y02976*
X03209Y02981*
X03204Y02985*
X03197Y02986*
G37*
G36*
X04794Y02824D02*
X04788Y02823D01*
X04782Y02819*
X04779Y02814*
X04777Y02808*
X04779Y02801*
X04782Y02796*
X04788Y02793*
X04794Y02791*
X048Y02793*
X04805Y02796*
X04809Y02801*
X0481Y02808*
X04809Y02814*
X04805Y02819*
X048Y02823*
X04794Y02824*
G37*
G36*
X04503Y02806D02*
X04497Y02804D01*
X04492Y02801*
X04488Y02796*
X04487Y02789*
X04488Y02783*
X04492Y02778*
X04497Y02774*
X04503Y02773*
X04509Y02774*
X04515Y02778*
X04518Y02783*
X04519Y02789*
X04518Y02796*
X04515Y02801*
X04509Y02804*
X04503Y02806*
G37*
G36*
X02146Y02769D02*
X0214Y02768D01*
X02135Y02764*
X02131Y02759*
X0213Y02753*
X02131Y02746*
X02135Y02741*
X0214Y02737*
X02146Y02736*
X02153Y02737*
X02158Y02741*
X02161Y02746*
X02163Y02753*
X02161Y02759*
X02158Y02764*
X02153Y02768*
X02146Y02769*
G37*
G36*
X02692Y02737D02*
X02686Y02736D01*
X02681Y02732*
X02677Y02727*
X02676Y02721*
X02677Y02715*
X02681Y02709*
X02686Y02706*
X02692Y02705*
X02699Y02706*
X02704Y02709*
X02707Y02715*
X02709Y02721*
X02707Y02727*
X02704Y02732*
X02699Y02736*
X02692Y02737*
G37*
G36*
X02394Y02736D02*
X02388Y02735D01*
X02383Y02732*
X02379Y02726*
X02378Y0272*
X02379Y02714*
X02383Y02708*
X02388Y02705*
X02394Y02704*
X024Y02705*
X02406Y02708*
X02409Y02714*
X02411Y0272*
X02409Y02726*
X02406Y02732*
X024Y02735*
X02394Y02736*
G37*
G36*
X02494Y02712D02*
X02488Y02711D01*
X02483Y02707*
X02479Y02702*
X02478Y02696*
X02479Y02689*
X02483Y02684*
X02488Y02681*
X02488Y02679*
Y02678*
X02488Y02675*
X02483Y02672*
X02479Y02667*
X02478Y02661*
X02479Y02654*
X02483Y02649*
X02488Y02645*
X02494Y02644*
X02501Y02645*
X02506Y02649*
X02509Y02654*
X02511Y02661*
X02509Y02667*
X02506Y02672*
X02501Y02675*
X02501Y02678*
Y02679*
X02501Y02681*
X02506Y02684*
X02509Y02689*
X02511Y02696*
X02509Y02702*
X02506Y02707*
X02501Y02711*
X02494Y02712*
G37*
G36*
X02958Y02637D02*
X02952Y02636D01*
X02947Y02632*
X02943Y02627*
X02942Y02621*
X02943Y02614*
X02947Y02609*
X02952Y02605*
X02958Y02604*
X02965Y02605*
X0297Y02609*
X02973Y02614*
X02975Y02621*
X02973Y02627*
X0297Y02632*
X02965Y02636*
X02958Y02637*
G37*
G36*
X02429D02*
X02422Y02636D01*
X02417Y02632*
X02414Y02627*
X02412Y02621*
X02414Y02614*
X02417Y02609*
X02422Y02605*
X02429Y02604*
X02435Y02605*
X0244Y02609*
X02444Y02614*
X02445Y02621*
X02444Y02627*
X0244Y02632*
X02435Y02636*
X02429Y02637*
G37*
G36*
X02252Y02629D02*
X02246Y02628D01*
X0224Y02625*
X02237Y02619*
X02236Y02613*
X02237Y02607*
X02239Y02603*
X02236Y02599*
X02231Y026*
X02225Y02599*
X0222Y02595*
X02216Y0259*
X02215Y02584*
X02216Y02577*
X0222Y02572*
X02225Y02569*
X02231Y02567*
X02237Y02569*
X02243Y02572*
X02246Y02577*
X02248Y02584*
X02246Y0259*
X02244Y02594*
X02247Y02598*
X02252Y02597*
X02258Y02598*
X02263Y02602*
X02267Y02607*
X02268Y02613*
X02267Y02619*
X02263Y02625*
X02258Y02628*
X02252Y02629*
G37*
G36*
X02821Y02617D02*
X02815Y02616D01*
X0281Y02612*
X02806Y02607*
X02805Y02601*
X02806Y02594*
X0281Y02589*
X02815Y02585*
X02821Y02584*
X02828Y02585*
X02833Y02589*
X02836Y02594*
X02838Y02601*
X02836Y02607*
X02833Y02612*
X02828Y02616*
X02821Y02617*
G37*
G36*
X03623Y02603D02*
X03617Y02602D01*
X03612Y02598*
X03608Y02593*
X03607Y02587*
X03608Y0258*
X03612Y02575*
X03617Y02571*
X03623Y0257*
X0363Y02571*
X03635Y02575*
X03638Y0258*
X0364Y02587*
X03638Y02593*
X03635Y02598*
X0363Y02602*
X03623Y02603*
G37*
G36*
X04298Y02641D02*
X04286Y02639D01*
X04275Y02635*
X04266Y02627*
X04258Y02618*
X04254Y02607*
X04252Y02595*
X04254Y02583*
X04258Y02572*
X04266Y02562*
X04275Y02555*
X04286Y02551*
X04298Y02549*
X0431Y02551*
X04321Y02555*
X04331Y02562*
X04338Y02572*
X04342Y02583*
X04344Y02595*
X04342Y02607*
X04338Y02618*
X04331Y02627*
X04321Y02635*
X0431Y02639*
X04298Y02641*
G37*
G36*
X0418D02*
X04168Y02639D01*
X04157Y02635*
X04148Y02627*
X0414Y02618*
X04136Y02607*
X04134Y02595*
X04136Y02583*
X0414Y02572*
X04148Y02562*
X04157Y02555*
X04168Y02551*
X0418Y02549*
X04192Y02551*
X04203Y02555*
X04212Y02562*
X0422Y02572*
X04224Y02583*
X04226Y02595*
X04224Y02607*
X0422Y02618*
X04212Y02627*
X04203Y02635*
X04192Y02639*
X0418Y02641*
G37*
G36*
X04062D02*
X0405Y02639D01*
X04039Y02635*
X04029Y02627*
X04022Y02618*
X04018Y02607*
X04016Y02595*
X04018Y02583*
X04022Y02572*
X04029Y02562*
X04039Y02555*
X0405Y02551*
X04062Y02549*
X04074Y02551*
X04085Y02555*
X04094Y02562*
X04102Y02572*
X04106Y02583*
X04108Y02595*
X04106Y02607*
X04102Y02618*
X04094Y02627*
X04085Y02635*
X04074Y02639*
X04062Y02641*
G37*
G36*
X06284Y02517D02*
X06278Y02516D01*
X06273Y02512*
X06269Y02507*
X06268Y02501*
X06269Y02494*
X06273Y02489*
X06278Y02485*
X06284Y02484*
X06291Y02485*
X06296Y02489*
X06299Y02494*
X06301Y02501*
X06299Y02507*
X06296Y02512*
X06291Y02516*
X06284Y02517*
G37*
G36*
X0102Y02497D02*
X01014Y02496D01*
X01009Y02492*
X01005Y02487*
X01004Y02481*
X01005Y02474*
X01009Y02469*
X01014Y02465*
X0102Y02464*
X01027Y02465*
X01032Y02469*
X01035Y02474*
X01037Y02481*
X01035Y02487*
X01032Y02492*
X01027Y02496*
X0102Y02497*
G37*
G36*
X02624Y02477D02*
X02618Y02476D01*
X02613Y02472*
X02609Y02467*
X02608Y02461*
X02609Y02454*
X02609Y02454*
X02606Y0245*
X02606Y02451*
X02599Y02452*
X02593Y02451*
X02588Y02447*
X02584Y02442*
X02583Y02436*
X02584Y02431*
X02583Y0243*
X02581Y02427*
X0258Y02427*
X02575Y02428*
X02569Y02427*
X02564Y02423*
X0256Y02418*
X02559Y02412*
X0256Y02405*
X02564Y024*
X02569Y02396*
X02575Y02395*
X02582Y02396*
X02587Y024*
X0259Y02405*
X02592Y02412*
X02591Y02416*
X02591Y02417*
X02594Y0242*
X02595Y0242*
X02599Y02419*
X02606Y0242*
X02611Y02424*
X02614Y02429*
X02616Y02436*
X02614Y02442*
X02614Y02442*
X02618Y02446*
X02618Y02445*
X02624Y02444*
X02631Y02445*
X02636Y02449*
X02639Y02454*
X02641Y02461*
X02639Y02467*
X02636Y02472*
X02631Y02476*
X02624Y02477*
G37*
G36*
X02272Y0248D02*
X02265Y02478D01*
X0226Y02475*
X02256Y0247*
X02255Y02463*
X02256Y02457*
X0226Y02452*
X02265Y02448*
X02272Y02447*
X02278Y02448*
X02283Y02452*
X02287Y02457*
X02288Y02463*
X02287Y0247*
X02283Y02475*
X02278Y02478*
X02272Y0248*
G37*
G36*
X02525Y02479D02*
X02519Y02478D01*
X02514Y02474*
X0251Y02469*
X02509Y02463*
X0251Y02456*
X02514Y02451*
X02519Y02447*
X02525Y02446*
X02532Y02447*
X02537Y02451*
X0254Y02456*
X02542Y02463*
X0254Y02469*
X02537Y02474*
X02532Y02478*
X02525Y02479*
G37*
G36*
X05578Y02534D02*
X05566Y02533D01*
X05555Y02528*
X05545Y02521*
X05538Y02511*
X05533Y025*
X05532Y02489*
X05533Y02477*
X05538Y02466*
X05545Y02456*
X05555Y02449*
X05566Y02444*
X05578Y02443*
X0559Y02444*
X05601Y02449*
X0561Y02456*
X05617Y02466*
X05622Y02477*
X05624Y02489*
X05622Y025*
X05617Y02511*
X0561Y02521*
X05601Y02528*
X0559Y02533*
X05578Y02534*
G37*
G36*
X02948Y02472D02*
X02942Y02471D01*
X02937Y02467*
X02933Y02462*
X02932Y02456*
X02933Y02449*
X02937Y02444*
X02942Y0244*
X02948Y02439*
X02955Y0244*
X0296Y02444*
X02963Y02449*
X02965Y02456*
X02963Y02462*
X0296Y02467*
X02955Y02471*
X02948Y02472*
G37*
G36*
X0299Y02457D02*
X02983Y02456D01*
X02976Y02452*
X02972Y02445*
X02971Y02438*
X02972Y02431*
X02976Y02424*
X02983Y0242*
X0299Y02419*
X02997Y0242*
X03004Y02424*
X03008Y02431*
X03009Y02438*
X03008Y02445*
X03004Y02452*
X02997Y02456*
X0299Y02457*
G37*
G36*
X02203D02*
X02195Y02456D01*
X02189Y02452*
X02185Y02445*
X02183Y02438*
X02185Y02431*
X02189Y02424*
X02195Y0242*
X02203Y02419*
X0221Y0242*
X02216Y02424*
X0222Y02431*
X02222Y02438*
X0222Y02445*
X02216Y02452*
X0221Y02456*
X02203Y02457*
G37*
G36*
X03617Y02553D02*
X03604Y02552D01*
X03592Y02548*
X0358Y02542*
X0357Y02533*
X03561Y02523*
X03555Y02512*
X03551Y02499*
X0355Y02486*
X03551Y02473*
X03555Y0246*
X03561Y02448*
X0357Y02438*
X0358Y0243*
X03592Y02424*
X03604Y0242*
X03617Y02418*
X03631Y0242*
X03643Y02424*
X03655Y0243*
X03665Y02438*
X03673Y02448*
X0368Y0246*
X03684Y02473*
X03685Y02486*
X03684Y02499*
X0368Y02512*
X03673Y02523*
X03665Y02533*
X03655Y02542*
X03643Y02548*
X03631Y02552*
X03617Y02553*
G37*
G36*
X01651D02*
X01638Y02552D01*
X01626Y02548*
X01614Y02542*
X01604Y02533*
X01595Y02523*
X01589Y02512*
X01585Y02499*
X01584Y02486*
X01585Y02473*
X01589Y0246*
X01595Y02448*
X01604Y02438*
X01614Y0243*
X01626Y02424*
X01638Y0242*
X01651Y02418*
X01665Y0242*
X01677Y02424*
X01689Y0243*
X01699Y02438*
X01707Y02448*
X01714Y0246*
X01718Y02473*
X01719Y02486*
X01718Y02499*
X01714Y02512*
X01707Y02523*
X01699Y02533*
X01689Y02542*
X01677Y02548*
X01665Y02552*
X01651Y02553*
G37*
G36*
X00199Y02545D02*
X00187Y02544D01*
X00175Y0254*
X00164Y02534*
X00154Y02526*
X00146Y02516*
X0014Y02505*
X00136Y02493*
X00135Y02481*
X00136Y02468*
X0014Y02456*
X00146Y02445*
X00154Y02435*
X00164Y02427*
X00175Y02421*
X00187Y02417*
X00199Y02416*
X00212Y02417*
X00224Y02421*
X00235Y02427*
X00245Y02435*
X00253Y02445*
X00259Y02456*
X00262Y02468*
X00264Y02481*
X00262Y02493*
X00259Y02505*
X00253Y02516*
X00245Y02526*
X00235Y02534*
X00224Y0254*
X00212Y02544*
X00199Y02545*
G37*
G36*
X02894Y02447D02*
X02888Y02446D01*
X02883Y02442*
X02879Y02437*
X02878Y02431*
X02879Y02424*
X02883Y02419*
X02888Y02415*
X02894Y02414*
X02901Y02415*
X02906Y02419*
X02907*
X02909Y02416*
X02914Y02412*
X0292Y02411*
X02927Y02412*
X02932Y02416*
X02935Y02421*
X02937Y02428*
X02935Y02434*
X02932Y02439*
X02927Y02443*
X0292Y02444*
X02914Y02443*
X02909Y02439*
X02908*
X02906Y02442*
X02901Y02446*
X02894Y02447*
G37*
G36*
X04039Y02422D02*
X04033Y02421D01*
X04028Y02417*
X04024Y02412*
X04023Y02406*
X04024Y02399*
X04028Y02394*
X04033Y0239*
X04039Y02389*
X04046Y0239*
X04051Y02394*
X04054Y02399*
X04056Y02406*
X04054Y02412*
X04051Y02417*
X04046Y02421*
X04039Y02422*
G37*
G36*
X03498Y02357D02*
X03492Y02356D01*
X03487Y02352*
X03483Y02347*
X03482Y02341*
X03483Y02334*
X03487Y02329*
X03492Y02325*
X03498Y02324*
X03505Y02325*
X0351Y02329*
X03513Y02334*
X03515Y02341*
X03513Y02347*
X0351Y02352*
X03505Y02356*
X03498Y02357*
G37*
G36*
X02726Y02309D02*
X0272Y02308D01*
X02715Y02304*
X02713Y02301*
X02709Y02304*
X02702Y02305*
X02696Y02304*
X02691Y023*
X02687Y02295*
X02686Y0229*
X02682Y02291*
X0268Y02297*
X02677Y02302*
X02672Y02306*
X02665Y02307*
X02659Y02306*
X02654Y02302*
X0265Y02297*
X02649Y02291*
X02648Y02289*
X02645Y0229*
X02639Y02289*
X02634Y02285*
X0263Y0228*
X02629Y02274*
X0263Y02267*
X02634Y02262*
X02639Y02258*
X02645Y02257*
X02652Y02258*
X02657Y02262*
X0266Y02267*
X02662Y02274*
X02663Y02275*
X02665Y02274*
X02672Y02275*
X02677Y02279*
X0268Y02284*
X02681Y02289*
X02686Y02289*
X02687Y02282*
X02691Y02277*
X02696Y02273*
X02702Y02272*
X02709Y02273*
X02714Y02277*
X02716Y0228*
X0272Y02277*
X02726Y02276*
X02733Y02277*
X02738Y02281*
X02741Y02286*
X02743Y02293*
X02741Y02299*
X02738Y02304*
X02733Y02308*
X02726Y02309*
G37*
G36*
X02475Y02307D02*
X02469Y02306D01*
X02464Y02302*
X02462Y02299*
X02457Y02297*
X02455Y02297*
X0245Y02298*
X02444Y02297*
X02439Y02293*
X02435Y02288*
X02434Y02282*
X02435Y02275*
X02439Y0227*
X02444Y02266*
X0245Y02265*
X02457Y02266*
X02462Y0227*
X02465Y02275*
X0247Y02275*
X02475Y02274*
X02482Y02275*
X02487Y02279*
X0249Y02284*
X02492Y02291*
X0249Y02297*
X02487Y02302*
X02482Y02306*
X02475Y02307*
G37*
G36*
X02803Y02323D02*
X02797Y02322D01*
X02792Y02318*
X02788Y02313*
X02787Y02307*
X02788Y023*
X02792Y02295*
X02797Y02291*
X02803Y0229*
X0281Y02291*
X02815Y02295*
X02818Y023*
X0282Y02307*
X02818Y02313*
X02815Y02318*
X0281Y02322*
X02803Y02323*
G37*
G36*
X02985Y02303D02*
X02979Y02302D01*
X02974Y02298*
X0297Y02293*
X02969Y02287*
X0297Y0228*
X02974Y02275*
X02979Y02271*
X02985Y0227*
X02992Y02271*
X02997Y02275*
X03Y0228*
X03002Y02287*
X03Y02293*
X02997Y02298*
X02992Y02302*
X02985Y02303*
G37*
G36*
X02942Y02302D02*
X02936Y02301D01*
X02931Y02297*
X02927Y02292*
X02926Y02286*
X02927Y02279*
X02931Y02274*
X02936Y0227*
X02942Y02269*
X02949Y0227*
X02954Y02274*
X02957Y02279*
X02959Y02286*
X02957Y02292*
X02954Y02297*
X02949Y02301*
X02942Y02302*
G37*
G36*
X05327Y02346D02*
X05317Y02345D01*
X05308Y02341*
X053Y02334*
X05294Y02326*
X0529Y02317*
X05288Y02307*
X0529Y02297*
X05294Y02288*
X053Y0228*
X05308Y02273*
X05317Y02269*
X05327Y02268*
X05337Y02269*
X05347Y02273*
X05355Y0228*
X05361Y02288*
X05365Y02297*
X05366Y02307*
X05365Y02317*
X05361Y02326*
X05355Y02334*
X05347Y02341*
X05337Y02345*
X05327Y02346*
G37*
G36*
X04927D02*
X04917Y02345D01*
X04908Y02341*
X049Y02334*
X04894Y02326*
X0489Y02317*
X04888Y02307*
X0489Y02297*
X04894Y02288*
X049Y0228*
X04908Y02273*
X04917Y02269*
X04927Y02268*
X04937Y02269*
X04947Y02273*
X04955Y0228*
X04961Y02288*
X04965Y02297*
X04966Y02307*
X04965Y02317*
X04961Y02326*
X04955Y02334*
X04947Y02341*
X04937Y02345*
X04927Y02346*
G37*
G36*
X04727D02*
X04717Y02345D01*
X04708Y02341*
X047Y02334*
X04694Y02326*
X0469Y02317*
X04688Y02307*
X0469Y02297*
X04694Y02288*
X047Y0228*
X04708Y02273*
X04717Y02269*
X04727Y02268*
X04737Y02269*
X04747Y02273*
X04755Y0228*
X04761Y02288*
X04765Y02297*
X04766Y02307*
X04765Y02317*
X04761Y02326*
X04755Y02334*
X04747Y02341*
X04737Y02345*
X04727Y02346*
G37*
G36*
X04327D02*
X04317Y02345D01*
X04308Y02341*
X043Y02334*
X04294Y02326*
X0429Y02317*
X04288Y02307*
X0429Y02297*
X04294Y02288*
X043Y0228*
X04308Y02273*
X04317Y02269*
X04327Y02268*
X04337Y02269*
X04347Y02273*
X04355Y0228*
X04361Y02288*
X04365Y02297*
X04366Y02307*
X04365Y02317*
X04361Y02326*
X04355Y02334*
X04347Y02341*
X04337Y02345*
X04327Y02346*
G37*
G36*
X02409Y0233D02*
X02403Y02329D01*
X02398Y02325*
X02394Y0232*
X02393Y02314*
X02394Y02307*
X02398Y02302*
X02399Y02301*
Y02295*
X02398Y02294*
X02394Y02289*
X02393Y02283*
X02394Y02276*
X02398Y02271*
X02403Y02267*
X02409Y02266*
X02416Y02267*
X02421Y02271*
X02424Y02276*
X02426Y02283*
X02424Y02289*
X02421Y02294*
X02419Y02295*
Y02301*
X02421Y02302*
X02424Y02307*
X02426Y02314*
X02424Y0232*
X02421Y02325*
X02416Y02329*
X02409Y0233*
G37*
G36*
X02579Y02297D02*
X02573Y02296D01*
X02568Y02292*
X02564Y02287*
X02563Y02281*
X02564Y02274*
X02568Y02269*
X02573Y02265*
X02579Y02264*
X02586Y02265*
X02591Y02269*
X02594Y02274*
X02596Y02281*
X02594Y02287*
X02591Y02292*
X02586Y02296*
X02579Y02297*
G37*
G36*
X03342Y02279D02*
X03336Y02278D01*
X03331Y02274*
X03327Y02269*
X03326Y02263*
X03327Y02256*
X03331Y02251*
X03336Y02247*
X03342Y02246*
X03349Y02247*
X03354Y02251*
X03357Y02256*
X03359Y02263*
X03357Y02269*
X03354Y02274*
X03349Y02278*
X03342Y02279*
G37*
G36*
X02841D02*
X02835Y02278D01*
X0283Y02274*
X02826Y02269*
X02825Y02263*
X02826Y02256*
X0283Y02251*
X02835Y02247*
X02841Y02246*
X02848Y02247*
X02853Y02251*
X02856Y02256*
X02858Y02263*
X02856Y02269*
X02853Y02274*
X02848Y02278*
X02841Y02279*
G37*
G36*
X00996Y02272D02*
X0099Y02271D01*
X00985Y02267*
X00981Y02262*
X0098Y02256*
X00981Y02249*
X00985Y02244*
X0099Y0224*
X00996Y02239*
X01003Y0224*
X01008Y02244*
X01011Y02249*
X01013Y02256*
X01011Y02262*
X01008Y02267*
X01003Y02271*
X00996Y02272*
G37*
G36*
X05634Y02252D02*
X05628Y02251D01*
X05623Y02247*
X05619Y02242*
X05618Y02236*
X05619Y02229*
X05623Y02224*
X05628Y0222*
X05634Y02219*
X05641Y0222*
X05646Y02224*
X05649Y02229*
X05651Y02236*
X05649Y02242*
X05646Y02247*
X05641Y02251*
X05634Y02252*
G37*
G36*
X02499D02*
X02493Y02251D01*
X02488Y02247*
X02484Y02242*
X02483Y02236*
X02484Y02229*
X02488Y02224*
X02493Y0222*
X02499Y02219*
X02506Y0222*
X02511Y02224*
X02514Y02229*
X02516Y02236*
X02514Y02242*
X02511Y02247*
X02506Y02251*
X02499Y02252*
G37*
G36*
X0233Y02231D02*
X02324Y0223D01*
X02319Y02226*
X02315Y02221*
X02314Y02215*
X02315Y02208*
X02319Y02203*
X02324Y02199*
X0233Y02198*
X02337Y02199*
X02342Y02203*
X02345Y02208*
X02347Y02215*
X02345Y02221*
X02342Y02226*
X02337Y0223*
X0233Y02231*
G37*
G36*
X05577Y0223D02*
X05571Y02229D01*
X05566Y02225*
X05562Y0222*
X05561Y02214*
X05562Y02207*
X05566Y02202*
X05571Y02198*
X05577Y02197*
X05584Y02198*
X05589Y02202*
X05592Y02207*
X05594Y02214*
X05592Y0222*
X05589Y02225*
X05584Y02229*
X05577Y0223*
G37*
G36*
X06424Y02197D02*
X06418Y02196D01*
X06413Y02192*
X06409Y02187*
X06408Y02181*
X06409Y02174*
X06413Y02169*
X06418Y02165*
X06424Y02164*
X06431Y02165*
X06436Y02169*
X06439Y02174*
X06441Y02181*
X06439Y02187*
X06436Y02192*
X06431Y02196*
X06424Y02197*
G37*
G36*
X01754Y02142D02*
X01748Y02141D01*
X01743Y02137*
X01739Y02132*
X01738Y02126*
X01739Y02119*
X01743Y02114*
X01748Y0211*
X01754Y02109*
X01761Y0211*
X01766Y02114*
X01769Y02119*
X01771Y02126*
X01769Y02132*
X01766Y02137*
X01761Y02141*
X01754Y02142*
G37*
G36*
X01619Y02137D02*
X01613Y02136D01*
X01608Y02132*
X01604Y02127*
X01603Y02121*
X01604Y02114*
X01608Y02109*
X01613Y02105*
X01619Y02104*
X01626Y02105*
X01631Y02109*
X01634Y02114*
X01636Y02121*
X01634Y02127*
X01631Y02132*
X01626Y02136*
X01619Y02137*
G37*
G36*
X01696Y02116D02*
X01689Y02114D01*
X01683Y0211*
X01679Y02104*
X01677Y02097*
X01679Y02089*
X01683Y02083*
X01689Y02079*
X01696Y02078*
X01704Y02079*
X0171Y02083*
X01714Y02089*
X01716Y02097*
X01714Y02104*
X0171Y0211*
X01704Y02114*
X01696Y02116*
G37*
G36*
X01884Y02087D02*
X01878Y02086D01*
X01873Y02082*
X01869Y02077*
X01868Y02071*
X01869Y02064*
X01873Y02059*
X01878Y02055*
X01884Y02054*
X01891Y02055*
X01896Y02059*
X01899Y02064*
X01901Y02071*
X01899Y02077*
X01896Y02082*
X01891Y02086*
X01884Y02087*
G37*
G36*
X01568Y02084D02*
X01561Y02082D01*
X01556Y02079*
X01553Y02073*
X01551Y02067*
X01553Y02061*
X01556Y02056*
X01561Y02052*
X01568Y02051*
X01574Y02052*
X01579Y02056*
X01583Y02061*
X01584Y02067*
X01583Y02073*
X01579Y02079*
X01574Y02082*
X01568Y02084*
G37*
G36*
X03571Y02116D02*
X03564Y02114D01*
X03558Y0211*
X03554Y02104*
X03552Y02097*
X03554Y02089*
X03558Y02083*
X03564Y02079*
X03568Y02078*
Y02073*
X03565Y02073*
X0356Y02069*
X03556Y02064*
X03555Y02058*
X03556Y02051*
X03558Y02049*
X03559Y02045*
X03558Y02041*
X03556Y02039*
X03555Y02033*
X03556Y02026*
X0356Y02021*
X03565Y02017*
X03571Y02016*
X03578Y02017*
X03583Y02021*
X03586Y02026*
X03588Y02033*
X03586Y02039*
X03585Y02041*
X03583Y02045*
X03585Y02049*
X03586Y02051*
X03588Y02058*
X03586Y02064*
X03583Y02069*
X03578Y02073*
X03575Y02073*
Y02078*
X03579Y02079*
X03585Y02083*
X03589Y02089*
X0359Y02097*
X03589Y02104*
X03585Y0211*
X03579Y02114*
X03571Y02116*
G37*
G36*
X02409Y01983D02*
X02403Y01982D01*
X02398Y01978*
X02394Y01973*
X02393Y01967*
X02394Y0196*
X02396Y01958*
X02392Y01955*
X02391Y01956*
X02384Y01957*
X02378Y01956*
X02373Y01952*
X02369Y01947*
X02368Y01941*
X02369Y01934*
X02373Y01929*
X02378Y01925*
X02384Y01924*
X02391Y01925*
X02396Y01929*
X02399Y01934*
X02401Y01941*
X02399Y01947*
X02398Y01949*
X02402Y01952*
X02403Y01951*
X02409Y0195*
X02416Y01951*
X02421Y01955*
X02424Y0196*
X02426Y01967*
X02424Y01973*
X02421Y01978*
X02416Y01982*
X02409Y01983*
G37*
G36*
X03298Y01987D02*
X03292Y01986D01*
X03287Y01982*
X03283Y01977*
X03282Y01971*
X03283Y01964*
X03287Y01959*
X03292Y01955*
X03298Y01954*
X03305Y01955*
X0331Y01959*
X03313Y01964*
X03315Y01971*
X03313Y01977*
X0331Y01982*
X03305Y01986*
X03298Y01987*
G37*
G36*
X01009Y01972D02*
X01003Y01971D01*
X00998Y01967*
X00994Y01962*
X00993Y01956*
X00994Y01949*
X00998Y01944*
X01003Y0194*
X01009Y01939*
X01016Y0194*
X01021Y01944*
X01024Y01949*
X01026Y01956*
X01024Y01962*
X01021Y01967*
X01016Y01971*
X01009Y01972*
G37*
G36*
X02299Y01932D02*
X02293Y01931D01*
X02288Y01927*
X02284Y01922*
X02283Y01916*
X02284Y01909*
X02288Y01904*
X02293Y019*
X02299Y01899*
X02306Y019*
X02311Y01904*
X02314Y01909*
X02316Y01916*
X02314Y01922*
X02311Y01927*
X02306Y01931*
X02299Y01932*
G37*
G36*
X00199Y0202D02*
X00187Y02019D01*
X00175Y02015*
X00164Y02009*
X00154Y02001*
X00146Y01991*
X0014Y0198*
X00136Y01968*
X00135Y01956*
X00136Y01943*
X0014Y01931*
X00146Y0192*
X00154Y0191*
X00164Y01902*
X00175Y01896*
X00187Y01892*
X00199Y01891*
X00212Y01892*
X00224Y01896*
X00235Y01902*
X00245Y0191*
X00253Y0192*
X00259Y01931*
X00262Y01943*
X00264Y01956*
X00262Y01968*
X00259Y0198*
X00253Y01991*
X00245Y02001*
X00235Y02009*
X00224Y02015*
X00212Y02019*
X00199Y0202*
G37*
G36*
X03554Y01907D02*
X03548Y01906D01*
X03543Y01902*
X03539Y01897*
X03538Y01891*
X03539Y01884*
X03543Y01879*
X03548Y01875*
X03554Y01874*
X03561Y01875*
X03566Y01879*
X03569Y01884*
X03571Y01891*
X03569Y01897*
X03566Y01902*
X03561Y01906*
X03554Y01907*
G37*
G36*
X03392Y01887D02*
X03386Y01886D01*
X03381Y01882*
X03377Y01877*
X03376Y01871*
X03377Y01864*
X03381Y01859*
X03386Y01855*
X03392Y01854*
X03399Y01855*
X03404Y01859*
X03407Y01864*
X03409Y01871*
X03407Y01877*
X03404Y01882*
X03399Y01886*
X03392Y01887*
G37*
G36*
X03439Y01887D02*
X03433Y01886D01*
X03427Y01882*
X03424Y01877*
X03422Y0187*
X03424Y01864*
X03427Y01859*
X03433Y01855*
X03439Y01854*
X03445Y01855*
X0345Y01859*
X03454Y01864*
X03455Y0187*
X03454Y01877*
X0345Y01882*
X03445Y01886*
X03439Y01887*
G37*
G36*
X03804Y01856D02*
X03798Y01855D01*
X03793Y01851*
X03789Y01846*
X03788Y0184*
X03789Y01833*
X03793Y01828*
X03798Y01824*
X03804Y01823*
X03811Y01824*
X03816Y01828*
X03819Y01833*
X03821Y0184*
X03819Y01846*
X03816Y01851*
X03811Y01855*
X03804Y01856*
G37*
G36*
X03329Y01842D02*
X03322Y01841D01*
X03317Y01837*
X03314Y01832*
X03312Y01826*
X03314Y01819*
X03317Y01814*
X03322Y0181*
X03329Y01809*
X03335Y0181*
X0334Y01814*
X03344Y01819*
X03345Y01826*
X03344Y01832*
X0334Y01837*
X03335Y01841*
X03329Y01842*
G37*
G36*
X01393Y01833D02*
X01387Y01832D01*
X01382Y01828*
X01378Y01823*
X01377Y01816*
X01378Y0181*
X01382Y01805*
X01387Y01801*
X01393Y018*
X01399Y01801*
X01405Y01805*
X01408Y0181*
X0141Y01816*
X01408Y01823*
X01405Y01828*
X01399Y01832*
X01393Y01833*
G37*
G36*
X03944Y01832D02*
X03938Y01831D01*
X03933Y01827*
X03929Y01822*
X03928Y01816*
X03929Y01809*
X03933Y01804*
X03938Y018*
X03944Y01799*
X03951Y018*
X03956Y01804*
X03959Y01809*
X03961Y01816*
X03959Y01822*
X03956Y01827*
X03951Y01831*
X03944Y01832*
G37*
G36*
X03056Y01828D02*
X0305Y01826D01*
X03045Y01823*
X03041Y01818*
X0304Y01811*
X03041Y01805*
X03045Y018*
X0305Y01796*
X03056Y01795*
X03063Y01796*
X03068Y018*
X03071Y01805*
X03073Y01811*
X03071Y01818*
X03068Y01823*
X03063Y01826*
X03056Y01828*
G37*
G36*
X01879D02*
X01873Y01826D01*
X01868Y01823*
X01864Y01818*
X01863Y01811*
X01864Y01805*
X01868Y018*
X01873Y01796*
X01879Y01795*
X01886Y01796*
X01891Y018*
X01895Y01805*
X01896Y01811*
X01895Y01818*
X01891Y01823*
X01886Y01826*
X01879Y01828*
G37*
G36*
X04064Y01812D02*
X04058Y01811D01*
X04053Y01807*
X04049Y01802*
X04048Y01796*
X04049Y01789*
X04053Y01784*
X04058Y0178*
X04064Y01779*
X04071Y0178*
X04076Y01784*
X04079Y01789*
X04081Y01796*
X04079Y01802*
X04076Y01807*
X04071Y01811*
X04064Y01812*
G37*
G36*
X02579Y01806D02*
X02573Y01805D01*
X02568Y01801*
X02564Y01796*
X02563Y0179*
X02564Y01783*
X02568Y01778*
X02573Y01774*
X02579Y01773*
X02586Y01774*
X02591Y01778*
X02594Y01783*
X02596Y0179*
X02594Y01796*
X02591Y01801*
X02586Y01805*
X02579Y01806*
G37*
G36*
X02626Y01786D02*
X0262Y01785D01*
X02615Y01781*
X02611Y01776*
X0261Y0177*
X02611Y01763*
X02615Y01758*
X0262Y01754*
X02626Y01753*
X02633Y01754*
X02638Y01758*
X02641Y01763*
X02643Y0177*
X02641Y01776*
X02638Y01781*
X02633Y01785*
X02626Y01786*
G37*
G36*
X03719Y01782D02*
X03713Y01781D01*
X03708Y01777*
X03704Y01772*
X03703Y01766*
X03704Y01759*
X03708Y01754*
X03713Y0175*
X03719Y01749*
X03726Y0175*
X03731Y01754*
X03734Y01759*
X03736Y01766*
X03734Y01772*
X03731Y01777*
X03726Y01781*
X03719Y01782*
G37*
G36*
X02549Y01771D02*
X02543Y0177D01*
X02538Y01766*
X02534Y01761*
X02533Y01755*
X02534Y01748*
X02538Y01743*
X02543Y01739*
X02549Y01738*
X02556Y01739*
X02561Y01743*
X02564Y01748*
X02566Y01755*
X02564Y01761*
X02561Y01766*
X02556Y0177*
X02549Y01771*
G37*
G36*
X04134Y01767D02*
X04128Y01766D01*
X04123Y01762*
X04119Y01757*
X04118Y01751*
X04119Y01744*
X04123Y01739*
X04128Y01735*
X04134Y01734*
X04141Y01735*
X04146Y01739*
X04149Y01744*
X04151Y01751*
X04149Y01757*
X04146Y01762*
X04141Y01766*
X04134Y01767*
G37*
G36*
X02604Y0175D02*
X02598Y01749D01*
X02593Y01745*
X02589Y0174*
X02588Y01734*
X02589Y01727*
X02593Y01722*
X02598Y01718*
X02604Y01717*
X02611Y01718*
X02616Y01722*
X02619Y01727*
X02621Y01734*
X02619Y0174*
X02616Y01745*
X02611Y01749*
X02604Y0175*
G37*
G36*
X00988Y01733D02*
X00981Y01732D01*
X00976Y01729*
X00973Y01723*
X00971Y01717*
X00973Y01711*
X00976Y01705*
X00981Y01702*
X00988Y01701*
X00994Y01702*
X00999Y01705*
X01003Y01711*
X01004Y01717*
X01003Y01723*
X00999Y01729*
X00994Y01732*
X00988Y01733*
G37*
G36*
X03197Y0173D02*
X03191Y01729D01*
X03185Y01725*
X03182Y0172*
X0318Y01714*
X03182Y01707*
X03185Y01702*
X03191Y01698*
X03197Y01697*
X03203Y01698*
X03208Y01702*
X03212Y01707*
X03213Y01714*
X03212Y0172*
X03208Y01725*
X03203Y01729*
X03197Y0173*
G37*
G36*
X03589Y01727D02*
X03583Y01726D01*
X03578Y01722*
X03574Y01717*
X03573Y01711*
X03574Y01704*
X03578Y01699*
X03583Y01695*
X03589Y01694*
X03596Y01695*
X03601Y01699*
X03604Y01704*
X03606Y01711*
X03604Y01717*
X03601Y01722*
X03596Y01726*
X03589Y01727*
G37*
G36*
X01893Y01709D02*
X01887Y01708D01*
X01882Y01704*
X01878Y01699*
X01877Y01693*
X01878Y01686*
X01882Y01681*
X01887Y01677*
X01893Y01676*
X019Y01677*
X01905Y01681*
X01908Y01686*
X0191Y01693*
X01908Y01699*
X01905Y01704*
X019Y01708*
X01893Y01709*
G37*
G36*
X03803Y01707D02*
X03797Y01706D01*
X03792Y01702*
X03788Y01697*
X03787Y01691*
X03788Y01684*
X03792Y01679*
X03797Y01675*
X03803Y01674*
X0381Y01675*
X03815Y01679*
X03818Y01684*
X0382Y01691*
X03818Y01697*
X03815Y01702*
X0381Y01706*
X03803Y01707*
G37*
G36*
X03724Y01691D02*
X03718Y0169D01*
X03713Y01686*
X03709Y01681*
X03708Y01675*
X03709Y01668*
X03713Y01663*
X03718Y01659*
X03724Y01658*
X03731Y01659*
X03736Y01663*
X03739Y01668*
X03741Y01675*
X03739Y01681*
X03736Y01686*
X03731Y0169*
X03724Y01691*
G37*
G36*
X01822Y0169D02*
X01816Y01689D01*
X01811Y01685*
X01807Y0168*
X01806Y01674*
X01807Y01667*
X01811Y01662*
X01816Y01658*
X01822Y01657*
X01829Y01658*
X01834Y01662*
X01837Y01667*
X01839Y01674*
X01837Y0168*
X01834Y01685*
X01829Y01689*
X01822Y0169*
G37*
G36*
X03773Y01682D02*
X03767Y01681D01*
X03762Y01677*
X03758Y01672*
X03757Y01666*
X03758Y01659*
X03762Y01654*
X03767Y01651*
X03773Y01649*
X0378Y01651*
X03785Y01654*
X03788Y01659*
X0379Y01666*
X03788Y01672*
X03785Y01677*
X0378Y01681*
X03773Y01682*
G37*
G36*
X06844Y01677D02*
X06838Y01676D01*
X06833Y01672*
X06829Y01667*
X06828Y01661*
X06829Y01654*
X06833Y01649*
X06838Y01645*
X06844Y01644*
X06851Y01645*
X06856Y01649*
X06859Y01654*
X06861Y01661*
X06859Y01667*
X06856Y01672*
X06851Y01676*
X06844Y01677*
G37*
G36*
X03224Y01677D02*
X03218Y01676D01*
X03213Y01672*
X03209Y01667*
X03208Y01661*
X03209Y01655*
X03213Y01649*
X03218Y01646*
X03224Y01645*
X03231Y01646*
X03235Y01649*
X03239Y01649*
X03241Y01649*
X03246Y01645*
X03252Y01644*
X03259Y01645*
X03264Y01649*
X03267Y01654*
X03269Y01661*
X03267Y01667*
X03264Y01672*
X03259Y01676*
X03252Y01677*
X03246Y01676*
X03242Y01673*
X03238Y01672*
X03235Y01673*
X03231Y01676*
X03224Y01677*
G37*
G36*
X02666Y01656D02*
X0266Y01655D01*
X02655Y01651*
X02651Y01646*
X0265Y0164*
X02651Y01635*
X02647Y01631*
X02647Y01631*
X02643Y01632*
X02637Y01631*
X02632Y01627*
X02628Y01622*
X02627Y01616*
X02628Y01609*
X02632Y01604*
X02637Y016*
X02643Y01599*
X0265Y016*
X02655Y01604*
X02658Y01609*
X0266Y01616*
X02659Y0162*
X02662Y01624*
X02663Y01624*
X02666Y01623*
X02673Y01624*
X02678Y01628*
X02681Y01633*
X02683Y0164*
X02681Y01646*
X02678Y01651*
X02673Y01655*
X02666Y01656*
G37*
G36*
X04134Y01667D02*
X04128Y01666D01*
X04123Y01662*
X04119Y01657*
X04118Y01651*
X04119Y01644*
X04123Y01639*
X04128Y01635*
X04133Y01634*
X04135Y01631*
X04136Y01629*
X04136Y01629*
X04134Y01623*
X04136Y01617*
X04139Y01612*
X04145Y01608*
X04151Y01607*
X04157Y01608*
X04161Y01611*
X04164Y01607*
X04164Y01607*
X04163Y01601*
X04164Y01594*
X04168Y01589*
X04173Y01585*
X04179Y01584*
X04186Y01585*
X04191Y01589*
X04194Y01594*
X04196Y01601*
X04194Y01607*
X04191Y01612*
X04186Y01616*
X04179Y01617*
X04173Y01616*
X04169Y01613*
X04166Y01617*
X04166Y01617*
X04167Y01623*
X04166Y01629*
X04162Y01635*
X04157Y01638*
X04152Y01639*
X0415Y01643*
X04149Y01644*
X04149Y01644*
X04151Y01651*
X04149Y01657*
X04146Y01662*
X04141Y01666*
X04134Y01667*
G37*
G36*
X02719Y01607D02*
X02713Y01606D01*
X02708Y01602*
X02704Y01597*
X02703Y01591*
X02704Y01584*
X02708Y01579*
X02713Y01575*
X02719Y01574*
X02726Y01575*
X02731Y01579*
X02734Y01584*
X02736Y01591*
X02734Y01597*
X02731Y01602*
X02726Y01606*
X02719Y01607*
G37*
G36*
X03894Y01582D02*
X03888Y01581D01*
X03883Y01577*
X03879Y01572*
X03878Y01566*
X03879Y01559*
X03883Y01554*
X03888Y0155*
X03894Y01549*
X03901Y0155*
X03906Y01554*
X03909Y01559*
X03911Y01566*
X03909Y01572*
X03906Y01577*
X03901Y01581*
X03894Y01582*
G37*
G36*
X03969Y01568D02*
X03963Y01567D01*
X03958Y01563*
X03954Y01558*
X03953Y01552*
X03954Y01545*
X03958Y0154*
X03963Y01536*
X03969Y01535*
X03976Y01536*
X03978Y01538*
X03983Y01539*
X03985Y01537*
X03988Y01535*
X03994Y01534*
X04001Y01535*
X04006Y01539*
X04009Y01544*
X04011Y01551*
X04009Y01557*
X04006Y01562*
X04001Y01566*
X03994Y01567*
X03988Y01566*
X03983Y01562*
X03982*
X03981Y01563*
X03976Y01567*
X03969Y01568*
G37*
G36*
X04034Y01562D02*
X04028Y01561D01*
X04023Y01557*
X04019Y01552*
X04018Y01546*
X04019Y01539*
X04023Y01534*
X04028Y0153*
X04034Y01529*
X04041Y0153*
X04046Y01534*
X04049Y01539*
X04051Y01546*
X04049Y01552*
X04046Y01557*
X04041Y01561*
X04034Y01562*
G37*
G36*
X03924Y01552D02*
X03918Y01551D01*
X03913Y01547*
X03909Y01542*
X03908Y01536*
X03909Y01529*
X03913Y01524*
X03918Y0152*
X03924Y01519*
X03931Y0152*
X03936Y01524*
X03939Y01529*
X03941Y01536*
X03939Y01542*
X03936Y01547*
X03931Y01551*
X03924Y01552*
G37*
G36*
X02894Y01577D02*
X02888Y01576D01*
X02883Y01572*
X02879Y01567*
X02878Y01561*
X02879Y01554*
X02883Y01549*
X02888Y01545*
X02894Y01544*
X02901Y01545*
X02901Y01546*
X02904Y01542*
X02904Y01542*
X02903Y01536*
X02904Y01529*
X02908Y01524*
X02913Y0152*
X02919Y01519*
X02926Y0152*
X02931Y01524*
X02934Y01529*
X02936Y01536*
X02934Y01542*
X02931Y01547*
X02926Y01551*
X02919Y01552*
X02913Y01551*
X02913Y0155*
X02909Y01554*
X02909Y01554*
X02911Y01561*
X02909Y01567*
X02906Y01572*
X02901Y01576*
X02894Y01577*
G37*
G36*
X01719Y01552D02*
X01713Y01551D01*
X01708Y01547*
X01704Y01542*
X01703Y01536*
X01704Y01529*
X01708Y01524*
X01713Y0152*
X01719Y01519*
X01726Y0152*
X01731Y01524*
X01734Y01529*
X01736Y01536*
X01734Y01542*
X01731Y01547*
X01726Y01551*
X01719Y01552*
G37*
G36*
X01897Y01532D02*
X01891Y01531D01*
X01885Y01528*
X01882Y01522*
X0188Y01516*
X01882Y0151*
X01885Y01504*
X01891Y01501*
X01897Y015*
X01903Y01501*
X01908Y01504*
X01912Y0151*
X01913Y01516*
X01912Y01522*
X01908Y01528*
X01903Y01531*
X01897Y01532*
G37*
G36*
X04064Y01527D02*
X04058Y01526D01*
X04053Y01522*
X04049Y01517*
X04048Y01511*
X04049Y01504*
X04053Y01499*
X04058Y01495*
X04064Y01494*
X04071Y01495*
X04076Y01499*
X04079Y01504*
X04081Y01511*
X04079Y01517*
X04076Y01522*
X04071Y01526*
X04064Y01527*
G37*
G36*
X03864D02*
X03858Y01526D01*
X03853Y01522*
X03849Y01517*
X03848Y01511*
X03849Y01504*
X03853Y01499*
X03858Y01495*
X03864Y01494*
X03871Y01495*
X03876Y01499*
X03879Y01504*
X03881Y01511*
X03879Y01517*
X03876Y01522*
X03871Y01526*
X03864Y01527*
G37*
G36*
X02274Y01522D02*
X02268Y01521D01*
X02263Y01517*
X02259Y01512*
X02258Y01506*
X02259Y01499*
X02263Y01494*
X02268Y0149*
X02274Y01489*
X02281Y0149*
X02286Y01494*
X02289Y01499*
X02291Y01506*
X02289Y01512*
X02286Y01517*
X02281Y01521*
X02274Y01522*
G37*
G36*
X03834Y01497D02*
X03828Y01496D01*
X03823Y01492*
X03819Y01487*
X03818Y01481*
X03819Y01474*
X03823Y01469*
X03828Y01465*
X03834Y01464*
X03841Y01465*
X03846Y01469*
X03849Y01474*
X03851Y01481*
X03849Y01487*
X03846Y01492*
X03841Y01496*
X03834Y01497*
G37*
G36*
X02694D02*
X02688Y01496D01*
X02683Y01492*
X02679Y01487*
X02678Y01481*
X02679Y01474*
X02683Y01469*
X02688Y01465*
X02694Y01464*
X02701Y01465*
X02706Y01469*
X02709Y01474*
X02711Y01481*
X02709Y01487*
X02706Y01492*
X02701Y01496*
X02694Y01497*
G37*
G36*
X03549Y01457D02*
X03543Y01456D01*
X03538Y01452*
X03534Y01447*
X03533Y01441*
X03534Y01434*
X03538Y01429*
X03543Y01425*
X03549Y01424*
X03556Y01425*
X03561Y01429*
X03564Y01434*
X03566Y01441*
X03564Y01447*
X03561Y01452*
X03556Y01456*
X03549Y01457*
G37*
G36*
X02446Y01453D02*
X0244Y01452D01*
X02435Y01448*
X02431Y01443*
X0243Y01437*
X02431Y0143*
X02435Y01425*
X0244Y01421*
X02446Y0142*
X02453Y01421*
X02458Y01425*
X02461Y0143*
X02463Y01437*
X02461Y01443*
X02458Y01448*
X02453Y01452*
X02446Y01453*
G37*
G36*
X01008Y01446D02*
X01002Y01445D01*
X00997Y01441*
X00993Y01436*
X00992Y0143*
X00993Y01423*
X00997Y01418*
X01002Y01414*
X01008Y01413*
X01015Y01414*
X0102Y01418*
X01023Y01423*
X01025Y0143*
X01023Y01436*
X0102Y01441*
X01015Y01445*
X01008Y01446*
G37*
G36*
X02083Y01427D02*
X02077Y01426D01*
X02072Y01423*
X02068Y01417*
X02067Y01411*
X02068Y01405*
X02068Y01405*
X02066Y01402*
X02065Y01401*
X02059Y01402*
X02053Y01401*
X02048Y01397*
X02044Y01392*
X02043Y01386*
X02044Y01379*
X02048Y01374*
X02053Y0137*
X02059Y01369*
X02066Y0137*
X02071Y01374*
X02074Y01379*
X02076Y01386*
X02074Y01392*
X02074Y01392*
X02076Y01395*
X02078Y01396*
X02083Y01395*
X0209Y01396*
X02095Y014*
X02098Y01405*
X021Y01411*
X02098Y01417*
X02095Y01423*
X0209Y01426*
X02083Y01427*
G37*
G36*
X03407Y01427D02*
X03401Y01426D01*
X03395Y01422*
X03392Y01417*
X0339Y01411*
X03392Y01405*
X03395Y014*
X03391Y01397*
X03386Y01401*
X03379Y01402*
X03373Y01401*
X03368Y01397*
X03364Y01392*
X03363Y01386*
X03364Y01379*
X03368Y01374*
X03373Y0137*
X03379Y01369*
X03385Y0137*
X03388Y01368*
X03389Y01367*
X03388Y01363*
X03389Y01357*
X03392Y01353*
X03392Y01352*
X03389Y01349*
X03388Y01349*
X03386Y01351*
X03379Y01352*
X03373Y01351*
X03368Y01347*
X03364Y01342*
X03363Y01336*
X03364Y01329*
X03368Y01324*
X03373Y0132*
X03379Y01319*
X03386Y0132*
X03391Y01324*
X03394Y01329*
X03396Y01336*
X03394Y01342*
X03392Y01345*
X03392Y01346*
X03395Y0135*
X03396Y01349*
X03398Y01348*
X03404Y01347*
X03411Y01348*
X03416Y01351*
X03419Y01357*
X03421Y01363*
X03419Y01369*
X03416Y01374*
X03411Y01378*
X03404Y01379*
X03399Y01378*
X03396Y0138*
X03395Y01382*
X03396Y01386*
X03394Y01392*
X03391Y01396*
X03395Y01399*
X03401Y01396*
X03407Y01395*
X03413Y01396*
X03418Y01399*
X03422Y01405*
X03423Y01411*
X03422Y01417*
X03418Y01422*
X03413Y01426*
X03407Y01427*
G37*
G36*
X00199Y01495D02*
X00187Y01494D01*
X00175Y0149*
X00164Y01484*
X00154Y01476*
X00146Y01466*
X0014Y01455*
X00136Y01443*
X00135Y01431*
X00136Y01418*
X0014Y01406*
X00146Y01395*
X00154Y01385*
X00164Y01377*
X00175Y01371*
X00187Y01367*
X00199Y01366*
X00212Y01367*
X00224Y01371*
X00235Y01377*
X00245Y01385*
X00253Y01395*
X00259Y01406*
X00262Y01418*
X00264Y01431*
X00262Y01443*
X00259Y01455*
X00253Y01466*
X00245Y01476*
X00235Y01484*
X00224Y0149*
X00212Y01494*
X00199Y01495*
G37*
G36*
X02028Y01377D02*
X02022Y01376D01*
X02017Y01373*
X02013Y01367*
X02012Y01361*
X02013Y01355*
X02013Y01355*
X02011Y01352*
X0201Y01351*
X02004Y01352*
X01998Y01351*
X01993Y01347*
X01989Y01342*
X01988Y01336*
X01989Y01329*
X01993Y01324*
X01998Y0132*
X02004Y01319*
X02011Y0132*
X02016Y01324*
X02019Y01329*
X02021Y01336*
X02019Y01342*
X02019Y01342*
X02021Y01345*
X02023Y01346*
X02028Y01345*
X02035Y01346*
X0204Y0135*
X02043Y01355*
X02045Y01361*
X02043Y01367*
X0204Y01373*
X02035Y01376*
X02028Y01377*
G37*
G36*
X02502Y01332D02*
X02496Y01331D01*
X02491Y01327*
X02487Y01322*
X02486Y01316*
X02487Y01309*
X02491Y01304*
X02496Y013*
X02502Y01299*
X02509Y013*
X02514Y01304*
X02517Y01309*
X02519Y01316*
X02517Y01322*
X02514Y01327*
X02509Y01331*
X02502Y01332*
G37*
G36*
X01696Y01329D02*
X01689Y01327D01*
X01683Y01323*
X01679Y01317*
X01677Y01309*
X01679Y01302*
X01683Y01296*
X01689Y01292*
X01696Y0129*
X01704Y01292*
X0171Y01296*
X01714Y01302*
X01716Y01309*
X01714Y01317*
X0171Y01323*
X01704Y01327*
X01696Y01329*
G37*
G36*
X03571Y01328D02*
X03564Y01327D01*
X03558Y01323*
X03554Y01317*
X03552Y01309*
X03554Y01302*
X03558Y01296*
X03564Y01292*
X03571Y0129*
X03579Y01292*
X03585Y01296*
X03589Y01302*
X0359Y01309*
X03589Y01317*
X03585Y01323*
X03579Y01327*
X03571Y01328*
G37*
G36*
X01798Y0132D02*
X01791Y01319D01*
X01786Y01315*
X01783Y0131*
X01781Y01304*
X01783Y01297*
X01786Y01292*
X01791Y01289*
X01798Y01287*
X01804Y01289*
X01809Y01292*
X01813Y01297*
X01814Y01304*
X01813Y0131*
X01809Y01315*
X01804Y01319*
X01798Y0132*
G37*
G36*
X02206Y01314D02*
X022Y01313D01*
X02195Y01309*
X02191Y01304*
X0219Y01298*
X02191Y01291*
X02195Y01286*
X022Y01282*
X02206Y01281*
X02213Y01282*
X02218Y01286*
X02221Y01291*
X02223Y01298*
X02221Y01304*
X02218Y01309*
X02213Y01313*
X02206Y01314*
G37*
G36*
X01567Y01301D02*
X01561Y013D01*
X01556Y01296*
X01552Y01291*
X01551Y01285*
X01552Y01279*
X01556Y01273*
X01561Y0127*
X01567Y01269*
X01574Y0127*
X01579Y01273*
X01582Y01279*
X01584Y01285*
X01582Y01291*
X01579Y01296*
X01574Y013*
X01567Y01301*
G37*
G36*
X00996Y01203D02*
X00989Y01202D01*
X00984Y01198*
X0098Y01193*
X00979Y01187*
X0098Y0118*
X00984Y01175*
X00989Y01171*
X00996Y0117*
X01002Y01171*
X01007Y01175*
X01011Y0118*
X01012Y01187*
X01011Y01193*
X01007Y01198*
X01002Y01202*
X00996Y01203*
G37*
G36*
X02826Y00992D02*
X0282Y00991D01*
X02815Y00987*
X0281*
X02805Y00991*
X02799Y00992*
X02792Y00991*
X02787Y00987*
X02786Y00986*
X0278*
X02779Y00987*
X02773Y00991*
X02767Y00992*
X02761Y00991*
X02756Y00987*
X02751*
X02746Y00991*
X0274Y00992*
X02733Y00991*
X02728Y00987*
X02727Y00986*
X02721*
X0272Y00987*
X02714Y00991*
X02708Y00992*
X02702Y00991*
X02697Y00987*
X02692*
X02687Y00991*
X02681Y00992*
X02674Y00991*
X02669Y00987*
X02668Y00986*
X02662*
X02661Y00987*
X02655Y00991*
X02649Y00992*
X02643Y00991*
X02638Y00987*
X02633*
X02628Y00991*
X02622Y00992*
X02615Y00991*
X0261Y00987*
X02606Y00982*
X02605Y00976*
X02606Y0097*
X0261Y00964*
X02615Y00961*
X02622Y0096*
X02628Y00961*
X02633Y00964*
X02638*
X02643Y00961*
X02649Y0096*
X02655Y00961*
X02661Y00964*
X02662Y00966*
X02668*
X02669Y00964*
X02674Y00961*
X02681Y0096*
X02687Y00961*
X02692Y00964*
X02697*
X02702Y00961*
X02708Y0096*
X02714Y00961*
X0272Y00964*
X02721Y00966*
X02727*
X02728Y00964*
X02733Y00961*
X0274Y0096*
X02746Y00961*
X02751Y00964*
X02756*
X02761Y00961*
X02767Y0096*
X02773Y00961*
X02779Y00964*
X0278Y00966*
X02786*
X02787Y00964*
X02792Y00961*
X02799Y0096*
X02805Y00961*
X0281Y00964*
X02815*
X0282Y00961*
X02826Y0096*
X02833Y00961*
X02838Y00964*
X02841Y0097*
X02843Y00976*
X02841Y00982*
X02838Y00987*
X02833Y00991*
X02826Y00992*
G37*
G36*
X04366Y01045D02*
X04289D01*
Y00968*
X04366*
Y01045*
G37*
G36*
X05327Y01046D02*
X05317Y01045D01*
X05308Y01041*
X053Y01034*
X05294Y01026*
X0529Y01017*
X05288Y01007*
X0529Y00997*
X05294Y00988*
X053Y0098*
X05308Y00973*
X05317Y00969*
X05327Y00968*
X05337Y00969*
X05347Y00973*
X05355Y0098*
X05361Y00988*
X05365Y00997*
X05366Y01007*
X05365Y01017*
X05361Y01026*
X05355Y01034*
X05347Y01041*
X05337Y01045*
X05327Y01046*
G37*
G36*
X05127D02*
X05117Y01045D01*
X05108Y01041*
X051Y01034*
X05094Y01026*
X0509Y01017*
X05088Y01007*
X0509Y00997*
X05094Y00988*
X051Y0098*
X05108Y00973*
X05117Y00969*
X05127Y00968*
X05137Y00969*
X05147Y00973*
X05155Y0098*
X05161Y00988*
X05165Y00997*
X05166Y01007*
X05165Y01017*
X05161Y01026*
X05155Y01034*
X05147Y01041*
X05137Y01045*
X05127Y01046*
G37*
G36*
X04927D02*
X04917Y01045D01*
X04908Y01041*
X049Y01034*
X04894Y01026*
X0489Y01017*
X04888Y01007*
X0489Y00997*
X04894Y00988*
X049Y0098*
X04908Y00973*
X04917Y00969*
X04927Y00968*
X04937Y00969*
X04947Y00973*
X04955Y0098*
X04961Y00988*
X04965Y00997*
X04966Y01007*
X04965Y01017*
X04961Y01026*
X04955Y01034*
X04947Y01041*
X04937Y01045*
X04927Y01046*
G37*
G36*
X0299Y00977D02*
X02983Y00976D01*
X02976Y00972*
X02972Y00965*
X02971Y00958*
X02972Y00951*
X02976Y00945*
X02983Y0094*
X0299Y00939*
X02997Y0094*
X03004Y00945*
X03008Y00951*
X03009Y00958*
X03008Y00965*
X03004Y00972*
X02997Y00976*
X0299Y00977*
G37*
G36*
X02203D02*
X02195Y00976D01*
X02189Y00972*
X02185Y00965*
X02183Y00958*
X02185Y00951*
X02189Y00945*
X02195Y0094*
X02203Y00939*
X0221Y0094*
X02216Y00945*
X0222Y00951*
X02222Y00958*
X0222Y00965*
X02216Y00972*
X0221Y00976*
X02203Y00977*
G37*
G36*
X02478Y00953D02*
X02472Y00952D01*
X02467Y00948*
X02463Y00943*
X02462Y00937*
X02463Y0093*
X02467Y00925*
X02472Y00921*
X02478Y0092*
X02485Y00921*
X0249Y00925*
X02493Y0093*
X02495Y00937*
X02493Y00943*
X0249Y00948*
X02485Y00952*
X02478Y00953*
G37*
G36*
X01004Y00922D02*
X00998Y00921D01*
X00993Y00917*
X00989Y00912*
X00988Y00906*
X00989Y00899*
X00993Y00894*
X00998Y0089*
X01004Y00889*
X01011Y0089*
X01016Y00894*
X01019Y00899*
X01021Y00906*
X01019Y00912*
X01016Y00917*
X01011Y00921*
X01004Y00922*
G37*
G36*
X03617Y00983D02*
X03604Y00982D01*
X03592Y00978*
X0358Y00972*
X0357Y00963*
X03561Y00953*
X03555Y00942*
X03551Y00929*
X0355Y00916*
X03551Y00903*
X03555Y0089*
X03561Y00878*
X0357Y00868*
X0358Y0086*
X03592Y00854*
X03604Y0085*
X03617Y00848*
X03631Y0085*
X03643Y00854*
X03655Y0086*
X03665Y00868*
X03673Y00878*
X0368Y0089*
X03684Y00903*
X03685Y00916*
X03684Y00929*
X0368Y00942*
X03673Y00953*
X03665Y00963*
X03655Y00972*
X03643Y00978*
X03631Y00982*
X03617Y00983*
G37*
G36*
X01652D02*
X01639Y00982D01*
X01627Y00978*
X01615Y00972*
X01605Y00963*
X01596Y00953*
X0159Y00942*
X01586Y00929*
X01585Y00916*
X01586Y00903*
X0159Y0089*
X01596Y00878*
X01605Y00868*
X01615Y0086*
X01627Y00854*
X01639Y0085*
X01652Y00848*
X01666Y0085*
X01678Y00854*
X0169Y0086*
X017Y00868*
X01708Y00878*
X01715Y0089*
X01719Y00903*
X0172Y00916*
X01719Y00929*
X01715Y00942*
X01708Y00953*
X017Y00963*
X0169Y00972*
X01678Y00978*
X01666Y00982*
X01652Y00983*
G37*
G36*
X05578Y00936D02*
X05566Y00934D01*
X05555Y0093*
X05545Y00923*
X05538Y00913*
X05533Y00902*
X05532Y0089*
X05533Y00878*
X05538Y00867*
X05545Y00858*
X05555Y0085*
X05566Y00846*
X05578Y00844*
X0559Y00846*
X05601Y0085*
X0561Y00858*
X05617Y00867*
X05622Y00878*
X05624Y0089*
X05622Y00902*
X05617Y00913*
X0561Y00923*
X05601Y0093*
X0559Y00934*
X05578Y00936*
G37*
G36*
X03979D02*
X03967Y00934D01*
X03956Y0093*
X03947Y00923*
X03939Y00913*
X03935Y00902*
X03933Y0089*
X03935Y00878*
X03939Y00867*
X03947Y00858*
X03956Y0085*
X03967Y00846*
X03979Y00844*
X03991Y00846*
X04002Y0085*
X04012Y00858*
X04019Y00867*
X04024Y00878*
X04025Y0089*
X04024Y00902*
X04019Y00913*
X04012Y00923*
X04002Y0093*
X03991Y00934*
X03979Y00936*
G37*
G36*
X00199Y0097D02*
X00187Y00969D01*
X00175Y00965*
X00164Y00959*
X00154Y00951*
X00146Y00941*
X0014Y0093*
X00136Y00918*
X00135Y00906*
X00136Y00893*
X0014Y00881*
X00146Y0087*
X00154Y0086*
X00164Y00852*
X00175Y00846*
X00187Y00842*
X00199Y00841*
X00212Y00842*
X00224Y00846*
X00235Y00852*
X00245Y0086*
X00253Y0087*
X00259Y00881*
X00262Y00893*
X00264Y00906*
X00262Y00918*
X00259Y0093*
X00253Y00941*
X00245Y00951*
X00235Y00959*
X00224Y00965*
X00212Y00969*
X00199Y0097*
G37*
G36*
X02759Y00811D02*
X02753Y0081D01*
X02748Y00806*
X02743*
X02738Y0081*
X02732Y00811*
X02726Y0081*
X0272Y00806*
X02717Y00801*
X02715Y00795*
X02717Y00789*
X0272Y00783*
X02726Y0078*
X02732Y00778*
X02738Y0078*
X02743Y00783*
X02748*
X02753Y0078*
X02759Y00778*
X02766Y0078*
X02771Y00783*
X02774Y00789*
X02776Y00795*
X02774Y00801*
X02771Y00806*
X02766Y0081*
X02759Y00811*
G37*
G36*
X02692D02*
X02686Y0081D01*
X02681Y00806*
X02676*
X02671Y0081*
X02665Y00811*
X02659Y0081*
X02653Y00806*
X0265Y00801*
X02649Y00795*
X0265Y00789*
X02653Y00783*
X02659Y0078*
X02665Y00778*
X02671Y0078*
X02676Y00783*
X02681*
X02686Y0078*
X02692Y00778*
X02699Y0078*
X02704Y00783*
X02707Y00789*
X02709Y00795*
X02707Y00801*
X02704Y00806*
X02699Y0081*
X02692Y00811*
G37*
G36*
X02625D02*
X02619Y0081D01*
X02614Y00806*
X02609*
X02604Y0081*
X02598Y00811*
X02592Y0081*
X02586Y00806*
X02583Y00801*
X02582Y00795*
X02583Y00789*
X02586Y00783*
X02592Y0078*
X02598Y00778*
X02604Y0078*
X02609Y00783*
X02614*
X02619Y0078*
X02625Y00778*
X02632Y0078*
X02637Y00783*
X02641Y00789*
X02642Y00795*
X02641Y00801*
X02637Y00806*
X02632Y0081*
X02625Y00811*
G37*
G36*
X02893D02*
X02887Y0081D01*
X02882Y00806*
X0288Y00805*
X02874*
X02873Y00806*
X02868Y0081*
X02862Y00811*
X02855Y0081*
X0285Y00806*
X02847Y00801*
X02847Y00801*
X02841*
X02841Y00801*
X02838Y00806*
X02833Y0081*
X02826Y00811*
X0282Y0081*
X02815Y00806*
X0281*
X02805Y0081*
X02799Y00811*
X02792Y0081*
X02787Y00806*
X02784Y00801*
X02782Y00795*
X02784Y00789*
X02787Y00783*
X02792Y0078*
X02799Y00778*
X02805Y0078*
X0281Y00783*
X02815*
X0282Y0078*
X02826Y00778*
X02833Y0078*
X02838Y00783*
X02841Y00789*
X02841Y00789*
X02847*
X02847Y00789*
X0285Y00783*
X02855Y0078*
X02862Y00778*
X02868Y0078*
X02873Y00783*
X02874Y00785*
X0288*
X02882Y00783*
X02887Y0078*
X02893Y00778*
X02899Y0078*
X02905Y00783*
X02908Y00789*
X0291Y00795*
X02908Y00801*
X02905Y00806*
X02899Y0081*
X02893Y00811*
G37*
G36*
X0099Y00703D02*
X00983Y00702D01*
X00978Y00698*
X00975Y00693*
X00973Y00687*
X00975Y0068*
X00978Y00675*
X00983Y00671*
X0099Y0067*
X00996Y00671*
X01001Y00675*
X01005Y0068*
X01006Y00687*
X01005Y00693*
X01001Y00698*
X00996Y00702*
X0099Y00703*
G37*
G36*
X02469Y00427D02*
X02463Y00426D01*
X02458Y00422*
X02454Y00417*
X02453Y0041*
X02454Y00404*
X02458Y00399*
X02463Y00395*
X02469Y00394*
X02476Y00395*
X02481Y00399*
X02484Y00404*
X02486Y0041*
X02484Y00417*
X02481Y00422*
X02476Y00426*
X02469Y00427*
G37*
G36*
X0298Y00425D02*
X02974Y00424D01*
X02968Y0042*
X02965Y00415*
X02964Y00409*
X02965Y00402*
X02968Y00397*
X02974Y00394*
X0298Y00392*
X02986Y00394*
X02991Y00397*
X02995Y00402*
X02996Y00409*
X02995Y00415*
X02991Y0042*
X02986Y00424*
X0298Y00425*
G37*
G36*
X03019Y00421D02*
X03013Y0042D01*
X03008Y00417*
X03004Y00411*
X03003Y00405*
X03004Y00399*
X03008Y00393*
X03013Y0039*
X03019Y00389*
X03025Y0039*
X03031Y00393*
X03034Y00399*
X03036Y00405*
X03034Y00411*
X03031Y00417*
X03025Y0042*
X03019Y00421*
G37*
G36*
X02821Y00424D02*
X02815Y00422D01*
X0281Y00419*
X02806Y00414*
X02805Y00407*
X02806Y00401*
X0281Y00396*
X02815Y00392*
X02821Y00391*
X02828Y00392*
X02833Y00396*
X02834Y00397*
X02835Y00398*
X0284Y00397*
X02842Y00393*
X02848Y0039*
X02854Y00389*
X0286Y0039*
X02865Y00393*
X02869Y00399*
X0287Y00405*
X02869Y00411*
X02865Y00417*
X0286Y0042*
X02854Y00421*
X02848Y0042*
X02842Y00417*
X02841Y00415*
X02841Y00415*
X02835Y00415*
X02833Y00419*
X02828Y00422*
X02821Y00424*
G37*
G36*
X02704Y00421D02*
X02698Y0042D01*
X02693Y00417*
X02689Y00411*
X02688Y00405*
X02689Y00399*
X02693Y00393*
X02698Y0039*
X02704Y00389*
X0271Y0039*
X02716Y00393*
X02719Y00399*
X02721Y00405*
X02719Y00411*
X02716Y00417*
X0271Y0042*
X02704Y00421*
G37*
G36*
X02665D02*
X02659Y0042D01*
X02653Y00417*
X0265Y00411*
X02649Y00405*
X0265Y00399*
X02653Y00393*
X02659Y0039*
X02665Y00389*
X02671Y0039*
X02676Y00393*
X0268Y00399*
X02681Y00405*
X0268Y00411*
X02676Y00417*
X02671Y0042*
X02665Y00421*
G37*
G36*
X02511D02*
X02505Y0042D01*
X025Y00417*
X02496Y00411*
X02495Y00405*
X02496Y00399*
X025Y00393*
X02505Y0039*
X02511Y00389*
X02518Y0039*
X02523Y00393*
X02526Y00399*
X02528Y00405*
X02526Y00411*
X02523Y00417*
X02518Y0042*
X02511Y00421*
G37*
G36*
X02389D02*
X02383Y0042D01*
X02378Y00417*
X02374Y00411*
X02373Y00405*
X02374Y00399*
X02378Y00393*
X02383Y0039*
X02389Y00389*
X02396Y0039*
X02401Y00393*
X02404Y00399*
X02406Y00405*
X02404Y00411*
X02401Y00417*
X02396Y0042*
X02389Y00421*
G37*
G36*
X0235D02*
X02344Y0042D01*
X02338Y00417*
X02335Y00411*
X02334Y00405*
X02335Y00399*
X02338Y00393*
X02344Y0039*
X0235Y00389*
X02356Y0039*
X02361Y00393*
X02365Y00399*
X02366Y00405*
X02365Y00411*
X02361Y00417*
X02356Y0042*
X0235Y00421*
G37*
G36*
X01872Y00303D02*
X01865Y00302D01*
X01862Y003*
X01858Y00302*
X01852Y00303*
X01846Y00302*
X01842Y003*
X01838Y00302*
X01832Y00303*
X01826Y00302*
X01821Y00298*
X01817Y00293*
X01816Y00287*
X01817Y00281*
X01821Y00275*
X01822Y00274*
Y00268*
X01821Y00267*
X01817Y00262*
X01816Y00255*
X01817Y00249*
X01821Y00244*
X01826Y0024*
X01832Y00239*
X01838Y0024*
X01842Y00243*
X01846Y0024*
X01852Y00239*
X01858Y0024*
X01862Y00243*
X01865Y0024*
X01872Y00239*
X01878Y0024*
X01883Y00244*
X01887Y00249*
X01888Y00255*
X01887Y00262*
X01883Y00267*
X01881Y00268*
Y00274*
X01883Y00275*
X01887Y00281*
X01888Y00287*
X01887Y00293*
X01883Y00298*
X01878Y00302*
X01872Y00303*
G37*
G36*
X02112D02*
X02105Y00302D01*
X021Y00298*
X02097Y00293*
X02097Y00293*
X02091*
X02091Y00293*
X02088Y00298*
X02083Y00302*
X02076Y00303*
X0207Y00302*
X02065Y00298*
X02061Y00293*
X0206Y00287*
X02061Y00281*
X02065Y00275*
X02067Y00274*
Y00268*
X02065Y00267*
X02061Y00262*
X0206Y00255*
X02061Y00249*
X02065Y00244*
X0207Y0024*
X02076Y00239*
X02083Y0024*
X02088Y00244*
X02091Y00249*
X02091Y0025*
X02097*
X02097Y00249*
X021Y00244*
X02105Y0024*
X02112Y00239*
X02118Y0024*
X02123Y00244*
X02127Y00249*
X02128Y00255*
X02127Y00262*
X02123Y00267*
X02121Y00268*
Y00274*
X02123Y00275*
X02127Y00281*
X02128Y00287*
X02127Y00293*
X02123Y00298*
X02118Y00302*
X02112Y00303*
G37*
G36*
X0261Y00295D02*
X02603Y00294D01*
X02598Y00291*
X02597Y00289*
X02591*
X0259Y00291*
X02584Y00294*
X02578Y00295*
X02572Y00294*
X02567Y00291*
X02563Y00285*
X02562Y00279*
X02563Y00273*
X02567Y00267*
X02572Y00264*
X02578Y00263*
X02584Y00264*
X0259Y00267*
X02591Y00269*
X02597*
X02598Y00267*
X02603Y00264*
X0261Y00263*
X02616Y00264*
X02621Y00267*
X02625Y00273*
X02626Y00279*
X02625Y00285*
X02621Y00291*
X02616Y00294*
X0261Y00295*
G37*
G36*
X02444D02*
X02438Y00294D01*
X02433Y00291*
X02432Y00289*
X02426*
X02424Y00291*
X02419Y00294*
X02413Y00295*
X02407Y00294*
X02401Y00291*
X02398Y00285*
X02397Y00279*
X02398Y00273*
X02401Y00267*
X02407Y00264*
X02413Y00263*
X02419Y00264*
X02424Y00267*
X02426Y00269*
X02432*
X02433Y00267*
X02438Y00264*
X02444Y00263*
X02451Y00264*
X02456Y00267*
X02459Y00273*
X02461Y00279*
X02459Y00285*
X02456Y00291*
X02451Y00294*
X02444Y00295*
G37*
G36*
X02937D02*
X0293Y00294D01*
X02925Y00291*
X02924Y00289*
X02918*
X02917Y00291*
X02911Y00294*
X02905Y00295*
X02899Y00294*
X02893Y00291*
X0289Y00285*
X02889Y00279*
X0289Y00273*
X02893Y00267*
X02899Y00264*
X02905Y00263*
X02911Y00264*
X02917Y00267*
X02918Y00269*
X02924*
X02925Y00267*
X0293Y00264*
X02937Y00263*
X02943Y00264*
X02948Y00267*
X02952Y00273*
X02953Y00279*
X02952Y00285*
X02948Y00291*
X02943Y00294*
X02937Y00295*
G37*
G36*
X02748Y00298D02*
X02742Y00297D01*
X02737Y00293*
X02733Y00288*
X02732Y00282*
X02733Y00276*
X02737Y0027*
X02742Y00267*
X02748Y00266*
X02755Y00267*
X0276Y0027*
X02766Y0027*
X02767Y00267*
X02773Y00264*
X02779Y00263*
X02785Y00264*
X02791Y00267*
X02794Y00273*
X02795Y00279*
X02794Y00285*
X02791Y00291*
X02785Y00294*
X02779Y00295*
X02773Y00294*
X02767Y00291*
X02762Y00291*
X0276Y00293*
X02755Y00297*
X02748Y00298*
G37*
G36*
X02151Y00303D02*
X02145Y00302D01*
X0214Y00298*
X02136Y00293*
X02135Y00287*
X02136Y00281*
X0214Y00275*
X02141Y00274*
Y00268*
X0214Y00267*
X02136Y00262*
X02135Y00255*
X02136Y00249*
X0214Y00244*
X02145Y0024*
X02151Y00239*
X02157Y0024*
X02163Y00244*
X02166Y00249*
X02167Y00255*
X02166Y00262*
X02163Y00267*
X02161Y00268*
Y00274*
X02163Y00275*
X02166Y00281*
X02167Y00287*
X02166Y00293*
X02163Y00298*
X02157Y00302*
X02151Y00303*
G37*
G36*
X00285Y00501D02*
X00264Y00499D01*
X00244Y00494*
X00224Y00486*
X00207Y00476*
X00191Y00462*
X00177Y00446*
X00166Y00428*
X00158Y00409*
X00153Y00388*
X00152Y00368*
X00153Y00347*
X00158Y00326*
X00166Y00307*
X00177Y00289*
X00191Y00273*
X00207Y0026*
X00224Y00249*
X00244Y00241*
X00264Y00236*
X00285Y00234*
X00306Y00236*
X00326Y00241*
X00346Y00249*
X00363Y0026*
X00379Y00273*
X00393Y00289*
X00404Y00307*
X00412Y00326*
X00417Y00347*
X00418Y00368*
X00417Y00388*
X00412Y00409*
X00404Y00428*
X00393Y00446*
X00379Y00462*
X00363Y00476*
X00346Y00486*
X00326Y00494*
X00306Y00499*
X00285Y00501*
G37*
%LNgrandmaster-3*%
%LPD*%
G54D143*
X00299Y01006D03*
Y00806D03*
X00099D03*
Y01006D03*
X00299Y02581D03*
Y02381D03*
X00099D03*
Y02581D03*
X00299Y02056D03*
Y01856D03*
X00099D03*
Y02056D03*
X00299Y01531D03*
Y01331D03*
X00099D03*
Y01531D03*
G54D158*
X05127Y02307D03*
G54D160*
X05578Y01689D03*
X03979Y02489D03*
G54D161*
X069Y03589D03*
X06734D03*
X06569D03*
G54D162*
X05934Y03937D03*
G54D163*
X06119Y04056D03*
G54D171*
X04039Y03784D03*
X02878Y00249D03*
X02957Y00251D03*
X02447Y00242D03*
X02606Y00931D03*
X02636Y00247D03*
X02799Y00251D03*
X02409Y01088D03*
X02311Y0109D03*
X02508Y00931D03*
X02409Y00932D03*
X02724Y01093D03*
X02784Y01094D03*
X02842Y01095D03*
X02546Y00244D03*
X03097Y00251D03*
X02606Y01091D03*
X03554Y01841D03*
X03719Y01996D03*
X01721Y0189D03*
X01671Y01792D03*
X01674Y01989D03*
X02508Y0109D03*
X03413Y01573D03*
X0167Y01595D03*
X02409Y02579D03*
X02586Y02569D03*
X01718Y01792D03*
X02881Y02566D03*
X03732Y01418D03*
X02253Y02279D03*
X02311Y00934D03*
X03554Y01991D03*
X01675Y01891D03*
X02783Y02429D03*
X03719Y01921D03*
X02665Y01092D03*
X02475Y02456D03*
X03414Y01805D03*
X02685Y02311D03*
X0359Y01662D03*
X02404Y02412D03*
X01716Y01399D03*
X01721Y01989D03*
X03549Y01413D03*
X02488Y02413D03*
X0167Y01694D03*
X02901Y01095D03*
X03594Y01514D03*
X03406Y01461D03*
X0341Y01713D03*
X02933Y00953D03*
X02871Y02297D03*
X02685Y02568D03*
X03554Y01941D03*
X02783Y02568D03*
X03718Y01713D03*
X01721Y01694D03*
X01671Y01399D03*
X02581Y02308D03*
X01718Y01497D03*
X01714Y01595D03*
X01671Y01497D03*
X02321Y02586D03*
X02034Y00246D03*
X01916Y00244D03*
X02309Y00246D03*
X0333Y03301D03*
X0412Y03594D03*
X03183Y03135D03*
X03277Y02963D03*
X02419Y02788D03*
X02413Y03295D03*
X02321Y03361D03*
X02631Y02876D03*
X02473Y0298D03*
X00937Y02317D03*
X01726Y04329D03*
X01788D03*
X04477Y03135D03*
X04064Y02722D03*
X06628Y01372D03*
X06974Y01939D03*
X03968Y01671D03*
X04131Y01686D03*
X03996Y01711D03*
X0396Y02724D03*
X06253Y02909D03*
X06647Y03129D03*
X04339Y02725D03*
X0383Y03762D03*
X03395Y04222D03*
X04272Y03135D03*
X02139Y03738D03*
X04208Y03135D03*
X06626Y03032D03*
X04152Y03135D03*
X02724Y03521D03*
X01248Y02D03*
X04068Y03135D03*
X02674Y03501D03*
X04234Y02725D03*
X06456Y03009D03*
X01691Y04079D03*
X03642Y00636D03*
X06476Y03231D03*
X04333Y03135D03*
X01261Y02482D03*
X04114Y03135D03*
X06648Y03341D03*
X02888Y04221D03*
X0337Y02888D03*
X02258Y03741D03*
X01749Y0411D03*
X0229Y04217D03*
X0388Y03109D03*
X03744Y03342D03*
X03717Y03072D03*
X05733Y03556D03*
X05676Y03546D03*
X03603Y00682D03*
X06548Y01531D03*
X06602Y01612D03*
Y01672D03*
Y01722D03*
X06601Y01777D03*
X06685Y01828D03*
X06699Y01881D03*
X06949Y02095D03*
X06607Y02176D03*
X06395Y02111D03*
X06048Y02171D03*
X06004Y02434D03*
X06274Y02391D03*
X06398Y02453D03*
X06397Y02501D03*
X06396Y02556D03*
X06397Y0261D03*
X06398Y02657D03*
X06372Y02909D03*
X0491Y04203D03*
X04387Y04206D03*
X03777Y04023D03*
X04085Y03892D03*
X04194Y03884D03*
X04431Y03135D03*
X0286Y03787D03*
X02724Y03729D03*
X03531Y0366D03*
X03269Y03788D03*
X01242Y01472D03*
X01256Y00942D03*
X00654Y0079D03*
X00655Y01028D03*
X00654Y01314D03*
X00653Y01551D03*
X00654Y01839D03*
Y02073D03*
Y02365D03*
X00653Y02593D03*
G54D172*
X02531Y03853D03*
Y0283D03*
X00149D03*
Y03853D03*
M02*